FILE_TYPE = MACRO_DRAWING;
SET COLOR_WIRE YELLOW;
SET COLOR_PROP ORANGE;
SET COLOR_DOT WHITE;
SET COLOR_ARC YELLOW;
SET COLOR_BODY GREEN;
SET COLOR_NOTE PURPLE;
SET PROP_DISPLAY VALUE;
SET PAGE_NUMBER P325;
FORCEADD UNIVERSAL_GND..1
(-2750 -2275);
FORCEPROP 3 LASTPIN (-2750 -2225) SIG_NAME AGND_HSC\g
J 0
(-2740 -2215);
DISPLAY 0.659574 (-2740 -2215);
PAINT MONO (-2740 -2215);
DISPLAY INVISIBLE (-2740 -2215);
FORCEPROP 1 LAST HDL_POWER AGND_HSC
J 1
(-2725 -2350);
DISPLAY 0.723404 (-2725 -2350);
PAINT GREEN (-2725 -2350);
FORCEPROP 2 LAST CDS_LIB logical_power
J 0
(-2750 -2275);
DISPLAY INVISIBLE (-2750 -2275);
FORCEPROP 1 LAST PATH I1
J 0
(-2675 -2275);
DISPLAY 0.872340 (-2675 -2275);
PAINT AQUA (-2675 -2275);
DISPLAY INVISIBLE (-2675 -2275);
FORCEADD OFFPAGE..4
R 2
(-2075 -1325);
FORCEPROP 2 LAST $XR2 303 
J 0
(-2567 -1325);
DISPLAY 0.638298 (-2567 -1325);
PAINT MONO (-2567 -1325);
FORCEPROP 2 LAST $XR1 302 
J 0
(-2447 -1325);
DISPLAY 0.638298 (-2447 -1325);
PAINT MONO (-2447 -1325);
FORCEPROP 2 LAST $XR0 301 
J 0
(-2327 -1325);
DISPLAY 0.638298 (-2327 -1325);
PAINT MONO (-2327 -1325);
FORCEPROP 1 LAST COMMENT_BODY TRUE
J 2
(-2050 -1425);
DISPLAY 0.872340 (-2050 -1425);
PAINT GREEN (-2050 -1425);
DISPLAY INVISIBLE (-2050 -1425);
FORCEPROP 1 LAST OFFPAGE TRUE
J 2
(-2400 -1450);
DISPLAY 0.872340 (-2400 -1450);
PAINT GREEN (-2400 -1450);
DISPLAY INVISIBLE (-2400 -1450);
FORCEPROP 2 LAST CDS_LIB standard
J 0
(-2075 -1325);
DISPLAY INVISIBLE (-2075 -1325);
FORCEPROP 2 LAST PATH I10
J 0
(-2325 -1275);
DISPLAY 1.021277 (-2325 -1275);
DISPLAY INVISIBLE (-2325 -1275);
FORCEADD Q_RES..2
(-2025 -1975);
FORCEPROP 1 LAST LOCATION PR3985
J 0
(-1970 -1825);
DISPLAY 0.723404 (-1970 -1825);
PAINT AQUA (-1970 -1825);
FORCEPROP 0 LAST $SEC 1
J 0
(-1950 -1775);
DISPLAY 0.680851 (-1950 -1775);
PAINT MONO (-1950 -1775);
DISPLAY INVISIBLE (-1950 -1775);
FORCEPROP 0 LAST CDS_SEC 1
J 0
(-1950 -1775);
DISPLAY 1.021277 (-1950 -1775);
DISPLAY INVISIBLE (-1950 -1775);
FORCEPROP 1 LASTPIN (-2025 -1875) $PN 1
J 0
(-2020 -1913);
DISPLAY 0.787234 (-2020 -1913);
PAINT MONO (-2020 -1913);
FORCEPROP 1 LASTPIN (-2025 -2075) $PN 2
J 0
(-2020 -2065);
DISPLAY 0.787234 (-2020 -2065);
PAINT MONO (-2020 -2065);
FORCEPROP 1 LAST VALUE 100K
J 0
(-1970 -1875);
DISPLAY 0.723404 (-1970 -1875);
PAINT SKYBLUE (-1970 -1875);
FORCEPROP 1 LAST PACK_TYPE 0402LF
J 0
(-1975 -2125);
DISPLAY 0.723404 (-1975 -2125);
PAINT SKYBLUE (-1975 -2125);
FORCEPROP 1 LAST TOLERANCE 1%
J 0
(-1970 -1925);
DISPLAY 0.723404 (-1970 -1925);
PAINT SKYBLUE (-1970 -1925);
FORCEPROP 1 LAST PART_NUMBER CS41002FB09
J 0
(-1975 -2075);
DISPLAY 0.723404 (-1975 -2075);
PAINT WHITE (-1975 -2075);
FORCEPROP 1 LAST MATERIAL EMPTY
J 0
(-1975 -2025);
DISPLAY 0.723404 (-1975 -2025);
PAINT RED (-1975 -2025);
FORCEPROP 1 LAST WATTAGE 1/16W
J 0
(-1975 -1975);
DISPLAY 0.723404 (-1975 -1975);
PAINT SKYBLUE (-1975 -1975);
FORCEPROP 2 LAST CDS_LIB pure_quanta
J 0
(-2025 -1975);
DISPLAY INVISIBLE (-2025 -1975);
FORCEPROP 1 LAST PATH I11
J 0
(-1975 -1800);
DISPLAY 0.978723 (-1975 -1800);
PAINT WHITE (-1975 -1800);
DISPLAY INVISIBLE (-1975 -1800);
FORCEADD Q_RES..2
(-1525 -1975);
FORCEPROP 1 LAST LOCATION PR3987
J 0
(-1470 -1825);
DISPLAY 0.723404 (-1470 -1825);
PAINT AQUA (-1470 -1825);
FORCEPROP 0 LAST $SEC 1
J 0
(-1450 -1775);
DISPLAY 0.680851 (-1450 -1775);
PAINT MONO (-1450 -1775);
DISPLAY INVISIBLE (-1450 -1775);
FORCEPROP 0 LAST CDS_SEC 1
J 0
(-1450 -1775);
DISPLAY 1.021277 (-1450 -1775);
DISPLAY INVISIBLE (-1450 -1775);
FORCEPROP 1 LASTPIN (-1525 -1875) $PN 1
J 0
(-1520 -1913);
DISPLAY 0.787234 (-1520 -1913);
PAINT MONO (-1520 -1913);
FORCEPROP 1 LASTPIN (-1525 -2075) $PN 2
J 0
(-1520 -2065);
DISPLAY 0.787234 (-1520 -2065);
PAINT MONO (-1520 -2065);
FORCEPROP 1 LAST PART_NUMBER CS22002BB01
J 0
(-1475 -2075);
DISPLAY 0.723404 (-1475 -2075);
PAINT WHITE (-1475 -2075);
FORCEPROP 1 LAST VALUE 2K
J 0
(-1470 -1875);
DISPLAY 0.723404 (-1470 -1875);
PAINT SKYBLUE (-1470 -1875);
FORCEPROP 1 LAST WATTAGE 1/16W
J 0
(-1475 -1975);
DISPLAY 0.723404 (-1475 -1975);
PAINT SKYBLUE (-1475 -1975);
FORCEPROP 1 LAST TOLERANCE 0.1%
J 0
(-1470 -1925);
DISPLAY 0.723404 (-1470 -1925);
PAINT SKYBLUE (-1470 -1925);
FORCEPROP 1 LAST MATERIAL EMPTY
J 0
(-1475 -2025);
DISPLAY 0.723404 (-1475 -2025);
PAINT RED (-1475 -2025);
FORCEPROP 1 LAST PACK_TYPE 0402LF
J 0
(-1475 -2125);
DISPLAY 0.723404 (-1475 -2125);
PAINT SKYBLUE (-1475 -2125);
FORCEPROP 2 LAST CDS_LIB pure_quanta
J 0
(-1525 -1975);
DISPLAY INVISIBLE (-1525 -1975);
FORCEPROP 1 LAST PATH I12
J 0
(-1475 -1800);
DISPLAY 0.978723 (-1475 -1800);
PAINT WHITE (-1475 -1800);
DISPLAY INVISIBLE (-1475 -1800);
FORCEADD Q_RES..2
(-1000 -1975);
FORCEPROP 1 LAST LOCATION PR3991
J 0
(-945 -1825);
DISPLAY 0.723404 (-945 -1825);
PAINT AQUA (-945 -1825);
FORCEPROP 0 LAST $SEC 1
J 0
(-925 -1775);
DISPLAY 0.680851 (-925 -1775);
PAINT MONO (-925 -1775);
DISPLAY INVISIBLE (-925 -1775);
FORCEPROP 0 LAST CDS_SEC 1
J 0
(-925 -1775);
DISPLAY 1.021277 (-925 -1775);
DISPLAY INVISIBLE (-925 -1775);
FORCEPROP 1 LASTPIN (-1000 -1875) $PN 1
J 0
(-995 -1913);
DISPLAY 0.787234 (-995 -1913);
PAINT MONO (-995 -1913);
FORCEPROP 1 LASTPIN (-1000 -2075) $PN 2
J 0
(-995 -2065);
DISPLAY 0.787234 (-995 -2065);
PAINT MONO (-995 -2065);
FORCEPROP 1 LAST TOLERANCE 0.1%
J 0
(-945 -1925);
DISPLAY 0.723404 (-945 -1925);
PAINT SKYBLUE (-945 -1925);
FORCEPROP 1 LAST PART_NUMBER CS22002BB01
J 0
(-950 -2075);
DISPLAY 0.723404 (-950 -2075);
PAINT WHITE (-950 -2075);
FORCEPROP 1 LAST VALUE 2K
J 0
(-945 -1875);
DISPLAY 0.723404 (-945 -1875);
PAINT SKYBLUE (-945 -1875);
FORCEPROP 1 LAST MATERIAL EMPTY
J 0
(-950 -2025);
DISPLAY 0.723404 (-950 -2025);
PAINT RED (-950 -2025);
FORCEPROP 1 LAST WATTAGE 1/16W
J 0
(-950 -1975);
DISPLAY 0.723404 (-950 -1975);
PAINT SKYBLUE (-950 -1975);
FORCEPROP 1 LAST PACK_TYPE 0402LF
J 0
(-950 -2125);
DISPLAY 0.723404 (-950 -2125);
PAINT SKYBLUE (-950 -2125);
FORCEPROP 2 LAST CDS_LIB pure_quanta
J 0
(-1000 -1975);
DISPLAY INVISIBLE (-1000 -1975);
FORCEPROP 1 LAST PATH I13
J 0
(-950 -1800);
DISPLAY 0.978723 (-950 -1800);
PAINT WHITE (-950 -1800);
DISPLAY INVISIBLE (-950 -1800);
FORCEADD Q_RES..1
(-1950 -1150);
FORCEPROP 1 LAST LOCATION PR3984
J 0
(-2250 -1150);
DISPLAY 0.723404 (-2250 -1150);
PAINT AQUA (-2250 -1150);
FORCEPROP 0 LAST $SEC 1
J 0
(-1900 -1075);
DISPLAY 0.680851 (-1900 -1075);
PAINT MONO (-1900 -1075);
DISPLAY INVISIBLE (-1900 -1075);
FORCEPROP 0 LAST CDS_SEC 1
J 0
(-1900 -1075);
DISPLAY 1.021277 (-1900 -1075);
DISPLAY INVISIBLE (-1900 -1075);
FORCEPROP 1 LASTPIN (-2050 -1150) $PN 1
J 0
(-2038 -1138);
DISPLAY 0.787234 (-2038 -1138);
PAINT MONO (-2038 -1138);
FORCEPROP 1 LASTPIN (-1850 -1150) $PN 2
J 0
(-1888 -1138);
DISPLAY 0.787234 (-1888 -1138);
PAINT MONO (-1888 -1138);
FORCEPROP 1 LAST PART_NUMBER CS41202FB05
J 0
(-1825 -1150);
DISPLAY 0.723404 (-1825 -1150);
PAINT WHITE (-1825 -1150);
FORCEPROP 1 LAST PACK_TYPE 0402LF
J 0
(-1825 -1225);
DISPLAY 0.723404 (-1825 -1225);
PAINT SKYBLUE (-1825 -1225);
FORCEPROP 1 LAST MATERIAL EMPTY
J 0
(-1900 -1275);
DISPLAY 0.723404 (-1900 -1275);
PAINT RED (-1900 -1275);
FORCEPROP 1 LAST WATTAGE 1/16W
J 2
(-1925 -1275);
DISPLAY 0.723404 (-1925 -1275);
PAINT SKYBLUE (-1925 -1275);
FORCEPROP 1 LAST TOLERANCE 1%
J 0
(-1925 -1225);
DISPLAY 0.723404 (-1925 -1225);
PAINT SKYBLUE (-1925 -1225);
FORCEPROP 1 LAST VALUE 120K
J 2
(-1975 -1225);
DISPLAY 0.723404 (-1975 -1225);
PAINT SKYBLUE (-1975 -1225);
FORCEPROP 2 LAST CDS_LIB pure_quanta
J 0
(-1950 -1150);
DISPLAY INVISIBLE (-1950 -1150);
FORCEPROP 1 LAST PATH I14
J 0
(-2000 -1000);
DISPLAY 0.978723 (-2000 -1000);
PAINT WHITE (-2000 -1000);
DISPLAY INVISIBLE (-2000 -1000);
FORCEADD OFFPAGE..5
(-1100 -1750);
FORCEPROP 2 LAST $XR2 301 
J 0
(-1355 -1786);
DISPLAY 0.638298 (-1355 -1786);
PAINT MONO (-1355 -1786);
FORCEPROP 2 LAST $XR1 303 
J 0
(-1475 -1750);
DISPLAY 0.638298 (-1475 -1750);
PAINT MONO (-1475 -1750);
FORCEPROP 2 LAST $XR0 302 
J 0
(-1355 -1750);
DISPLAY 0.638298 (-1355 -1750);
PAINT MONO (-1355 -1750);
FORCEPROP 2 LAST CDS_LIB standard
J 0
(-1100 -1750);
DISPLAY INVISIBLE (-1100 -1750);
FORCEPROP 1 LAST COMMENT_BODY TRUE
J 0
(-1000 -1825);
DISPLAY 1.170213 (-1000 -1825);
PAINT GREEN (-1000 -1825);
DISPLAY INVISIBLE (-1000 -1825);
FORCEPROP 1 LAST OFFPAGE TRUE
J 0
(-775 -1875);
DISPLAY 0.872340 (-775 -1875);
PAINT AQUA (-775 -1875);
DISPLAY INVISIBLE (-775 -1875);
FORCEPROP 2 LAST PATH I15
J 0
(-1350 -1700);
DISPLAY 1.021277 (-1350 -1700);
DISPLAY INVISIBLE (-1350 -1700);
FORCEADD Q_RES..1
(-1350 -1325);
FORCEPROP 1 LAST LOCATION PR3989
J 0
(-1650 -1325);
DISPLAY 0.723404 (-1650 -1325);
PAINT AQUA (-1650 -1325);
FORCEPROP 0 LAST $SEC 1
J 0
(-1225 -1250);
DISPLAY 0.680851 (-1225 -1250);
PAINT MONO (-1225 -1250);
DISPLAY INVISIBLE (-1225 -1250);
FORCEPROP 0 LAST CDS_SEC 1
J 0
(-1225 -1250);
DISPLAY 1.021277 (-1225 -1250);
DISPLAY INVISIBLE (-1225 -1250);
FORCEPROP 1 LASTPIN (-1450 -1325) $PN 1
J 0
(-1438 -1313);
DISPLAY 0.787234 (-1438 -1313);
PAINT MONO (-1438 -1313);
FORCEPROP 1 LASTPIN (-1250 -1325) $PN 2
J 0
(-1288 -1313);
DISPLAY 0.787234 (-1288 -1313);
PAINT MONO (-1288 -1313);
FORCEPROP 1 LAST PACK_TYPE 0402LF
J 0
(-1425 -1425);
DISPLAY 0.723404 (-1425 -1425);
PAINT SKYBLUE (-1425 -1425);
FORCEPROP 1 LAST MATERIAL EMPTY
J 0
(-1200 -1425);
DISPLAY 0.723404 (-1200 -1425);
PAINT RED (-1200 -1425);
FORCEPROP 1 LAST PART_NUMBER CS00002JB13
J 0
(-1675 -1375);
DISPLAY 0.723404 (-1675 -1375);
PAINT WHITE (-1675 -1375);
FORCEPROP 1 LAST VALUE 0
J 2
(-1175 -1300);
DISPLAY 0.723404 (-1175 -1300);
PAINT SKYBLUE (-1175 -1300);
FORCEPROP 1 LAST WATTAGE 1/16W
J 2
(-1475 -1425);
DISPLAY 0.723404 (-1475 -1425);
PAINT SKYBLUE (-1475 -1425);
FORCEPROP 1 LAST TOLERANCE 5%
J 0
(-1225 -1375);
DISPLAY 0.723404 (-1225 -1375);
PAINT SKYBLUE (-1225 -1375);
FORCEPROP 2 LAST CDS_LIB pure_quanta
J 0
(-1350 -1325);
DISPLAY INVISIBLE (-1350 -1325);
FORCEPROP 1 LAST PATH I16
J 0
(-1400 -1175);
DISPLAY 0.978723 (-1400 -1175);
PAINT WHITE (-1400 -1175);
DISPLAY INVISIBLE (-1400 -1175);
FORCEADD MP5991GLUZ..1
(-25 -1225);
FORCEPROP 1 LAST LOCATION PU297
J 0
(-350 -225);
DISPLAY 1.148936 (-350 -225);
PAINT GREEN (-350 -225);
FORCEPROP 2 LAST SEC 1
J 0
(-325 0);
DISPLAY 0.680851 (-325 0);
PAINT MONO (-325 0);
DISPLAY INVISIBLE (-325 0);
FORCEPROP 2 LASTPIN (-500 -1650) $PN 23
J 2
(-510 -1640);
DISPLAY 0.680851 (-510 -1640);
PAINT MONO (-510 -1640);
FORCEPROP 2 LASTPIN (450 -1300) $PN 3
J 0
(460 -1290);
DISPLAY 0.680851 (460 -1290);
PAINT MONO (460 -1290);
FORCEPROP 2 LASTPIN (450 -1400) $PN 6
J 0
(460 -1390);
DISPLAY 0.680851 (460 -1390);
PAINT MONO (460 -1390);
FORCEPROP 2 LASTPIN (-500 -1950) $PN 20
J 2
(-510 -1940);
DISPLAY 0.680851 (-510 -1940);
PAINT MONO (-510 -1940);
FORCEPROP 2 LASTPIN (450 -1600) $PN 5
J 0
(460 -1590);
DISPLAY 0.680851 (460 -1590);
PAINT MONO (460 -1590);
FORCEPROP 2 LASTPIN (-500 -1750) $PN 22
J 2
(-510 -1740);
DISPLAY 0.680851 (-510 -1740);
PAINT MONO (-510 -1740);
FORCEPROP 2 LASTPIN (-500 -1150) $PN 8
J 2
(-510 -1140);
DISPLAY 0.680851 (-510 -1140);
PAINT MONO (-510 -1140);
FORCEPROP 2 LASTPIN (450 -1500) $PN 7
J 0
(460 -1490);
DISPLAY 0.680851 (460 -1490);
PAINT MONO (460 -1490);
FORCEPROP 2 LASTPIN (-500 -1550) $PN 24
J 2
(-510 -1540);
DISPLAY 0.680851 (-510 -1540);
PAINT MONO (-510 -1540);
FORCEPROP 2 LASTPIN (-500 -1450) $PN 4
J 2
(-510 -1440);
DISPLAY 0.680851 (-510 -1440);
PAINT MONO (-510 -1440);
FORCEPROP 2 LASTPIN (-500 -1250) $PN 17
J 2
(-510 -1240);
DISPLAY 0.680851 (-510 -1240);
PAINT MONO (-510 -1240);
FORCEPROP 2 LASTPIN (450 -1800) $PN 19
J 0
(460 -1790);
DISPLAY 0.680851 (460 -1790);
PAINT MONO (460 -1790);
FORCEPROP 2 LASTPIN (-500 -1050) $PN 21
J 2
(-510 -1040);
DISPLAY 0.680851 (-510 -1040);
PAINT MONO (-510 -1040);
FORCEPROP 2 LASTPIN (-500 -500) $PN 9
J 2
(-510 -490);
DISPLAY 0.680851 (-510 -490);
PAINT MONO (-510 -490);
FORCEPROP 2 LASTPIN (-500 -550) $PN 10
J 2
(-510 -540);
DISPLAY 0.680851 (-510 -540);
PAINT MONO (-510 -540);
FORCEPROP 2 LASTPIN (-500 -600) $PN 11
J 2
(-510 -590);
DISPLAY 0.680851 (-510 -590);
PAINT MONO (-510 -590);
FORCEPROP 2 LASTPIN (-500 -650) $PN 12
J 2
(-510 -640);
DISPLAY 0.680851 (-510 -640);
PAINT MONO (-510 -640);
FORCEPROP 2 LASTPIN (-500 -700) $PN 13
J 2
(-510 -690);
DISPLAY 0.680851 (-510 -690);
PAINT MONO (-510 -690);
FORCEPROP 2 LASTPIN (-500 -750) $PN 14
J 2
(-510 -740);
DISPLAY 0.680851 (-510 -740);
PAINT MONO (-510 -740);
FORCEPROP 2 LASTPIN (-500 -800) $PN 15
J 2
(-510 -790);
DISPLAY 0.680851 (-510 -790);
PAINT MONO (-510 -790);
FORCEPROP 2 LASTPIN (-500 -850) $PN 16
J 2
(-510 -840);
DISPLAY 0.680851 (-510 -840);
PAINT MONO (-510 -840);
FORCEPROP 2 LASTPIN (-500 -900) $PN 33
J 2
(-510 -890);
DISPLAY 0.680851 (-510 -890);
PAINT MONO (-510 -890);
FORCEPROP 2 LASTPIN (450 -500) $PN 1
J 0
(460 -490);
DISPLAY 0.680851 (460 -490);
PAINT MONO (460 -490);
FORCEPROP 2 LASTPIN (450 -550) $PN 2
J 0
(460 -540);
DISPLAY 0.680851 (460 -540);
PAINT MONO (460 -540);
FORCEPROP 2 LASTPIN (450 -600) $PN 25
J 0
(460 -590);
DISPLAY 0.680851 (460 -590);
PAINT MONO (460 -590);
FORCEPROP 2 LASTPIN (450 -650) $PN 26
J 0
(460 -640);
DISPLAY 0.680851 (460 -640);
PAINT MONO (460 -640);
FORCEPROP 2 LASTPIN (450 -700) $PN 27
J 0
(460 -690);
DISPLAY 0.680851 (460 -690);
PAINT MONO (460 -690);
FORCEPROP 2 LASTPIN (450 -750) $PN 28
J 0
(460 -740);
DISPLAY 0.680851 (460 -740);
PAINT MONO (460 -740);
FORCEPROP 2 LASTPIN (450 -800) $PN 29
J 0
(460 -790);
DISPLAY 0.680851 (460 -790);
PAINT MONO (460 -790);
FORCEPROP 2 LASTPIN (450 -850) $PN 30
J 0
(460 -840);
DISPLAY 0.680851 (460 -840);
PAINT MONO (460 -840);
FORCEPROP 2 LASTPIN (450 -900) $PN 31
J 0
(460 -890);
DISPLAY 0.680851 (460 -890);
PAINT MONO (460 -890);
FORCEPROP 2 LASTPIN (450 -950) $PN 32
J 0
(460 -940);
DISPLAY 0.680851 (460 -940);
PAINT MONO (460 -940);
FORCEPROP 2 LASTPIN (450 -1700) $PN 18
J 0
(460 -1690);
DISPLAY 0.680851 (460 -1690);
PAINT MONO (460 -1690);
FORCEPROP 2 LAST VALUE MP5991GLU-Z
J 0
(-350 -325);
DISPLAY 1.021277 (-350 -325);
FORCEPROP 2 LAST PART_TYPE SMLF
J 0
(-350 -275);
DISPLAY 1.021277 (-350 -275);
FORCEPROP 1 LAST MATERIAL EMPTY
J 0
(-345 -418);
DISPLAY 0.723404 (-345 -418);
PAINT RED (-345 -418);
FORCEPROP 1 LAST PART_NUMBER AL005991A00
J 0
(-350 -375);
DISPLAY 0.723404 (-350 -375);
PAINT GREEN (-350 -375);
FORCEPROP 2 LAST SEC_TYPE 
J 0
(-325 0);
DISPLAY 1.021277 (-325 0);
DISPLAY INVISIBLE (-325 0);
FORCEPROP 2 LAST CDS_LIB pure_quanta
J 0
(-25 -1225);
DISPLAY INVISIBLE (-25 -1225);
FORCEPROP 1 LAST CDS_LMAN_SYM_OUTLINE -325,775,325,-775
J 0
(-25 -1225);
DISPLAY 0.468085 (-25 -1225);
PAINT GREEN (-25 -1225);
DISPLAY INVISIBLE (-25 -1225);
FORCEPROP 1 LAST NEEDS_NO_SIZE TRUE
J 0
(-25 -1225);
DISPLAY 0.723404 (-25 -1225);
PAINT GREEN (-25 -1225);
DISPLAY INVISIBLE (-25 -1225);
FORCEPROP 1 LAST PATH I17
J 0
(-25 -1225);
DISPLAY 0.723404 (-25 -1225);
PAINT GREEN (-25 -1225);
DISPLAY INVISIBLE (-25 -1225);
FORCEADD UNIVERSAL_POWER..1
(-1000 -350);
FORCEPROP 3 LASTPIN (-1000 -400) SIG_NAME P12V_PSU\g
J 0
(-990 -390);
DISPLAY 0.659574 (-990 -390);
PAINT MONO (-990 -390);
DISPLAY INVISIBLE (-990 -390);
FORCEPROP 1 LAST HDL_POWER P12V_PSU
J 1
(-1000 -300);
DISPLAY 0.723404 (-1000 -300);
PAINT GREEN (-1000 -300);
FORCEPROP 2 LAST ROOM AUX_SW
J 0
(-1000 -250);
DISPLAY 0.617021 (-1000 -250);
DISPLAY INVISIBLE (-1000 -250);
FORCEPROP 2 LAST BOM_COST MIO_VRD_SB
J 0
(-1000 -250);
DISPLAY 0.617021 (-1000 -250);
PAINT PURPLE (-1000 -250);
DISPLAY INVISIBLE (-1000 -250);
FORCEPROP 2 LAST CDS_LIB logical_power
J 0
(-1000 -350);
DISPLAY INVISIBLE (-1000 -350);
FORCEPROP 1 LAST PATH I18
J 0
(-950 -325);
DISPLAY 0.872340 (-950 -325);
PAINT AQUA (-950 -325);
DISPLAY INVISIBLE (-950 -325);
FORCEADD UNIVERSAL_GND..1
(-3650 1150);
FORCEPROP 3 LASTPIN (-3650 1200) SIG_NAME AGND_HSC\g
J 0
(-3640 1210);
DISPLAY 0.659574 (-3640 1210);
PAINT MONO (-3640 1210);
DISPLAY INVISIBLE (-3640 1210);
FORCEPROP 1 LAST HDL_POWER AGND_HSC
J 1
(-3625 1075);
DISPLAY 0.723404 (-3625 1075);
PAINT GREEN (-3625 1075);
FORCEPROP 2 LAST CDS_LIB logical_power
J 0
(-3650 1150);
DISPLAY INVISIBLE (-3650 1150);
FORCEPROP 1 LAST PATH I19
J 0
(-3575 1150);
DISPLAY 0.872340 (-3575 1150);
PAINT AQUA (-3575 1150);
DISPLAY INVISIBLE (-3575 1150);
FORCEADD Q_CAP..1
(-2750 -1975);
FORCEPROP 1 LAST LOCATION PC2225
J 0
(-2675 -1875);
DISPLAY 0.723404 (-2675 -1875);
PAINT AQUA (-2675 -1875);
FORCEPROP 0 LAST $SEC 1
J 0
(-2675 -1825);
DISPLAY 0.680851 (-2675 -1825);
PAINT MONO (-2675 -1825);
DISPLAY INVISIBLE (-2675 -1825);
FORCEPROP 0 LAST CDS_SEC 1
J 0
(-2675 -1825);
DISPLAY 1.021277 (-2675 -1825);
DISPLAY INVISIBLE (-2675 -1825);
FORCEPROP 1 LASTPIN (-2750 -1875) $PN 1
J 0
(-2740 -1895);
DISPLAY 0.787234 (-2740 -1895);
PAINT MONO (-2740 -1895);
FORCEPROP 1 LASTPIN (-2750 -2075) $PN 2
J 0
(-2740 -2095);
DISPLAY 0.787234 (-2740 -2095);
PAINT MONO (-2740 -2095);
FORCEPROP 1 LAST PART_NUMBER TMP_QCH12206KB14
J 0
(-2675 -2075);
DISPLAY 0.723404 (-2675 -2075);
PAINT WHITE (-2675 -2075);
FORCEPROP 1 LAST PACK_TYPE 0402
J 0
(-2675 -2125);
DISPLAY 0.723404 (-2675 -2125);
PAINT SKYBLUE (-2675 -2125);
FORCEPROP 1 LAST MATERIAL EMPTY
J 0
(-2675 -2025);
DISPLAY 0.723404 (-2675 -2025);
PAINT RED (-2675 -2025);
FORCEPROP 1 LAST VALUE 220PF
J 0
(-2675 -1925);
DISPLAY 0.723404 (-2675 -1925);
PAINT SKYBLUE (-2675 -1925);
FORCEPROP 1 LAST VOLTAGE 50V
J 0
(-2675 -1975);
DISPLAY 0.723404 (-2675 -1975);
PAINT SKYBLUE (-2675 -1975);
FORCEPROP 1 LAST TOLERANCE 10%
J 0
(-2700 -2025);
DISPLAY 0.978723 (-2700 -2025);
PAINT SKYBLUE (-2700 -2025);
DISPLAY INVISIBLE (-2700 -2025);
FORCEPROP 2 LAST CDS_LIB pure_quanta
J 0
(-2750 -1975);
DISPLAY INVISIBLE (-2750 -1975);
FORCEPROP 1 LAST PATH I2
J 0
(-2700 -1825);
DISPLAY 0.978723 (-2700 -1825);
PAINT WHITE (-2700 -1825);
DISPLAY INVISIBLE (-2700 -1825);
FORCEADD Q_CAP..1
(-3650 1450);
FORCEPROP 1 LAST LOCATION PC2596
J 0
(-3575 1600);
DISPLAY 0.723404 (-3575 1600);
PAINT AQUA (-3575 1600);
FORCEPROP 0 LAST $SEC 1
J 0
(-3575 1650);
DISPLAY 0.680851 (-3575 1650);
PAINT MONO (-3575 1650);
DISPLAY INVISIBLE (-3575 1650);
FORCEPROP 0 LAST CDS_SEC 1
J 0
(-3575 1650);
DISPLAY 1.021277 (-3575 1650);
DISPLAY INVISIBLE (-3575 1650);
FORCEPROP 1 LASTPIN (-3650 1550) $PN 1
J 0
(-3640 1530);
DISPLAY 0.787234 (-3640 1530);
PAINT MONO (-3640 1530);
FORCEPROP 1 LASTPIN (-3650 1350) $PN 2
J 0
(-3640 1330);
DISPLAY 0.787234 (-3640 1330);
PAINT MONO (-3640 1330);
FORCEPROP 1 LAST PACK_TYPE C0402
J 0
(-3575 1350);
DISPLAY 0.723404 (-3575 1350);
PAINT SKYBLUE (-3575 1350);
FORCEPROP 1 LAST MATERIAL X6S
J 0
(-3575 1450);
DISPLAY 0.723404 (-3575 1450);
PAINT SKYBLUE (-3575 1450);
FORCEPROP 1 LAST PART_NUMBER CH5104KEB02
J 0
(-3575 1400);
DISPLAY 0.723404 (-3575 1400);
PAINT WHITE (-3575 1400);
FORCEPROP 1 LAST VOLTAGE 25V
J 0
(-3575 1500);
DISPLAY 0.723404 (-3575 1500);
PAINT SKYBLUE (-3575 1500);
FORCEPROP 1 LAST VALUE 1UF
J 0
(-3575 1550);
DISPLAY 0.723404 (-3575 1550);
PAINT SKYBLUE (-3575 1550);
FORCEPROP 2 LAST CDS_LIB pure_quanta
J 0
(-3650 1450);
DISPLAY INVISIBLE (-3650 1450);
FORCEPROP 1 LAST TOLERANCE 10%
J 0
(-3600 1400);
DISPLAY 0.978723 (-3600 1400);
PAINT SKYBLUE (-3600 1400);
DISPLAY INVISIBLE (-3600 1400);
FORCEPROP 1 LAST PATH I20
J 0
(-3600 1600);
DISPLAY 0.978723 (-3600 1600);
PAINT WHITE (-3600 1600);
DISPLAY INVISIBLE (-3600 1600);
FORCEADD Q_RES..1
R 1
(-3650 1925);
FORCEPROP 1 LAST LOCATION PR3980
J 0
(-3575 2075);
DISPLAY 0.723404 (-3575 2075);
PAINT AQUA (-3575 2075);
FORCEPROP 0 LAST $SEC 1
R 1
J 0
(-3575 2125);
DISPLAY 0.680851 (-3575 2125);
PAINT MONO (-3575 2125);
DISPLAY INVISIBLE (-3575 2125);
FORCEPROP 0 LAST CDS_SEC 1
R 1
J 0
(-3575 2125);
DISPLAY 1.021277 (-3575 2125);
DISPLAY INVISIBLE (-3575 2125);
FORCEPROP 1 LASTPIN (-3650 1825) $PN 1
R 1
J 0
(-3662 1837);
DISPLAY 0.787234 (-3662 1837);
PAINT MONO (-3662 1837);
FORCEPROP 1 LASTPIN (-3650 2025) $PN 2
R 1
J 0
(-3662 1987);
DISPLAY 0.787234 (-3662 1987);
PAINT MONO (-3662 1987);
FORCEPROP 1 LAST MATERIAL CHIP
J 0
(-3575 1925);
DISPLAY 0.787234 (-3575 1925);
PAINT SKYBLUE (-3575 1925);
FORCEPROP 1 LAST PART_NUMBER CS00002JB13
J 0
(-3575 1825);
DISPLAY 0.723404 (-3575 1825);
PAINT WHITE (-3575 1825);
FORCEPROP 1 LAST WATTAGE 1/16W
J 0
(-3575 1875);
DISPLAY 0.723404 (-3575 1875);
PAINT SKYBLUE (-3575 1875);
FORCEPROP 1 LAST PACK_TYPE 0402LF
J 0
(-3575 1775);
DISPLAY 0.723404 (-3575 1775);
PAINT SKYBLUE (-3575 1775);
FORCEPROP 1 LAST TOLERANCE 5%
J 0
(-3575 1975);
DISPLAY 0.723404 (-3575 1975);
PAINT SKYBLUE (-3575 1975);
FORCEPROP 1 LAST VALUE 0
R 2
J 0
(-3550 2050);
DISPLAY 0.723404 (-3550 2050);
PAINT SKYBLUE (-3550 2050);
FORCEPROP 2 LAST CDS_LIB pure_quanta
J 0
(-3650 1925);
DISPLAY INVISIBLE (-3650 1925);
FORCEPROP 1 LAST PATH I21
R 1
J 0
(-3800 1875);
DISPLAY 0.978723 (-3800 1875);
PAINT WHITE (-3800 1875);
DISPLAY INVISIBLE (-3800 1875);
FORCEADD UNIVERSAL_GND..1
(-2750 500);
FORCEPROP 3 LASTPIN (-2750 550) SIG_NAME AGND_HSC\g
J 0
(-2740 560);
DISPLAY 0.659574 (-2740 560);
PAINT MONO (-2740 560);
DISPLAY INVISIBLE (-2740 560);
FORCEPROP 1 LAST HDL_POWER AGND_HSC
J 1
(-2725 425);
DISPLAY 0.723404 (-2725 425);
PAINT GREEN (-2725 425);
FORCEPROP 2 LAST CDS_LIB logical_power
J 0
(-2750 500);
DISPLAY INVISIBLE (-2750 500);
FORCEPROP 1 LAST PATH I22
J 0
(-2675 500);
DISPLAY 0.872340 (-2675 500);
PAINT AQUA (-2675 500);
DISPLAY INVISIBLE (-2675 500);
FORCEADD Q_CAP..1
(-2750 800);
FORCEPROP 1 LAST LOCATION PC2224
J 0
(-2675 900);
DISPLAY 0.723404 (-2675 900);
PAINT AQUA (-2675 900);
FORCEPROP 0 LAST $SEC 1
J 0
(-2675 950);
DISPLAY 0.680851 (-2675 950);
PAINT MONO (-2675 950);
DISPLAY INVISIBLE (-2675 950);
FORCEPROP 0 LAST CDS_SEC 1
J 0
(-2675 950);
DISPLAY 1.021277 (-2675 950);
DISPLAY INVISIBLE (-2675 950);
FORCEPROP 1 LASTPIN (-2750 900) $PN 1
J 0
(-2740 880);
DISPLAY 0.787234 (-2740 880);
PAINT MONO (-2740 880);
FORCEPROP 1 LASTPIN (-2750 700) $PN 2
J 0
(-2740 680);
DISPLAY 0.787234 (-2740 680);
PAINT MONO (-2740 680);
FORCEPROP 1 LAST MATERIAL EMPTY
J 0
(-2675 750);
DISPLAY 0.723404 (-2675 750);
PAINT RED (-2675 750);
FORCEPROP 1 LAST VALUE 220PF
J 0
(-2675 850);
DISPLAY 0.723404 (-2675 850);
PAINT SKYBLUE (-2675 850);
FORCEPROP 1 LAST VOLTAGE 50V
J 0
(-2675 800);
DISPLAY 0.723404 (-2675 800);
PAINT SKYBLUE (-2675 800);
FORCEPROP 1 LAST PACK_TYPE 0402
J 0
(-2675 650);
DISPLAY 0.723404 (-2675 650);
PAINT SKYBLUE (-2675 650);
FORCEPROP 1 LAST PART_NUMBER TMP_QCH12206KB14
J 0
(-2675 700);
DISPLAY 0.723404 (-2675 700);
PAINT WHITE (-2675 700);
FORCEPROP 1 LAST TOLERANCE 10%
J 0
(-2700 750);
DISPLAY 0.978723 (-2700 750);
PAINT SKYBLUE (-2700 750);
DISPLAY INVISIBLE (-2700 750);
FORCEPROP 2 LAST CDS_LIB pure_quanta
J 0
(-2750 800);
DISPLAY INVISIBLE (-2750 800);
FORCEPROP 1 LAST PATH I23
J 0
(-2700 950);
DISPLAY 0.978723 (-2700 950);
PAINT WHITE (-2700 950);
DISPLAY INVISIBLE (-2700 950);
FORCEADD OFFPAGE..4
R 2
(-2925 1325);
FORCEPROP 2 LAST $XR2 303 
J 0
(-3207 1289);
DISPLAY 0.638298 (-3207 1289);
PAINT MONO (-3207 1289);
FORCEPROP 2 LAST $XR1 302 
J 0
(-3327 1325);
DISPLAY 0.638298 (-3327 1325);
PAINT MONO (-3327 1325);
FORCEPROP 2 LAST $XR0 301 
J 0
(-3207 1325);
DISPLAY 0.638298 (-3207 1325);
PAINT MONO (-3207 1325);
FORCEPROP 1 LAST OFFPAGE TRUE
J 2
(-3250 1200);
DISPLAY 0.872340 (-3250 1200);
PAINT GREEN (-3250 1200);
DISPLAY INVISIBLE (-3250 1200);
FORCEPROP 1 LAST COMMENT_BODY TRUE
J 2
(-2900 1225);
DISPLAY 0.872340 (-2900 1225);
PAINT GREEN (-2900 1225);
DISPLAY INVISIBLE (-2900 1225);
FORCEPROP 2 LAST CDS_LIB standard
J 0
(-2925 1325);
DISPLAY INVISIBLE (-2925 1325);
FORCEPROP 2 LAST PATH I24
J 0
(-3200 1375);
DISPLAY 1.021277 (-3200 1375);
DISPLAY INVISIBLE (-3200 1375);
FORCEADD UNIVERSAL_GND..1
(-2775 1550);
FORCEPROP 3 LASTPIN (-2775 1600) SIG_NAME AGND_HSC\g
J 0
(-2765 1610);
DISPLAY 0.659574 (-2765 1610);
PAINT MONO (-2765 1610);
DISPLAY INVISIBLE (-2765 1610);
FORCEPROP 1 LAST HDL_POWER AGND_HSC
J 1
(-2750 1475);
DISPLAY 0.723404 (-2750 1475);
PAINT GREEN (-2750 1475);
FORCEPROP 2 LAST CDS_LIB logical_power
J 0
(-2775 1550);
DISPLAY INVISIBLE (-2775 1550);
FORCEPROP 1 LAST PATH I25
J 0
(-2700 1550);
DISPLAY 0.872340 (-2700 1550);
PAINT AQUA (-2700 1550);
DISPLAY INVISIBLE (-2700 1550);
FORCEADD OFFPAGE..4
R 2
(-2100 1225);
FORCEPROP 2 LAST $XR2 303 
J 0
(-2592 1225);
DISPLAY 0.638298 (-2592 1225);
PAINT MONO (-2592 1225);
FORCEPROP 2 LAST $XR1 302 
J 0
(-2472 1225);
DISPLAY 0.638298 (-2472 1225);
PAINT MONO (-2472 1225);
FORCEPROP 2 LAST $XR0 301 
J 0
(-2352 1225);
DISPLAY 0.638298 (-2352 1225);
PAINT MONO (-2352 1225);
FORCEPROP 2 LAST CDS_LIB standard
J 0
(-2100 1225);
DISPLAY INVISIBLE (-2100 1225);
FORCEPROP 1 LAST COMMENT_BODY TRUE
J 2
(-2075 1125);
DISPLAY 0.872340 (-2075 1125);
PAINT GREEN (-2075 1125);
DISPLAY INVISIBLE (-2075 1125);
FORCEPROP 1 LAST OFFPAGE TRUE
J 2
(-2425 1100);
DISPLAY 0.872340 (-2425 1100);
PAINT GREEN (-2425 1100);
DISPLAY INVISIBLE (-2425 1100);
FORCEPROP 2 LAST PATH I26
J 0
(-2350 1275);
DISPLAY 1.021277 (-2350 1275);
DISPLAY INVISIBLE (-2350 1275);
FORCEADD OFFPAGE..4
R 2
(-2075 1450);
FORCEPROP 2 LAST $XR2 303 
J 0
(-2567 1450);
DISPLAY 0.638298 (-2567 1450);
PAINT MONO (-2567 1450);
FORCEPROP 2 LAST $XR1 302 
J 0
(-2447 1450);
DISPLAY 0.638298 (-2447 1450);
PAINT MONO (-2447 1450);
FORCEPROP 2 LAST $XR0 301 
J 0
(-2327 1450);
DISPLAY 0.638298 (-2327 1450);
PAINT MONO (-2327 1450);
FORCEPROP 1 LAST COMMENT_BODY TRUE
J 2
(-2050 1350);
DISPLAY 0.872340 (-2050 1350);
PAINT GREEN (-2050 1350);
DISPLAY INVISIBLE (-2050 1350);
FORCEPROP 1 LAST OFFPAGE TRUE
J 2
(-2400 1325);
DISPLAY 0.872340 (-2400 1325);
PAINT GREEN (-2400 1325);
DISPLAY INVISIBLE (-2400 1325);
FORCEPROP 2 LAST CDS_LIB standard
J 0
(-2075 1450);
DISPLAY INVISIBLE (-2075 1450);
FORCEPROP 2 LAST PATH I27
J 0
(-2325 1500);
DISPLAY 1.021277 (-2325 1500);
DISPLAY INVISIBLE (-2325 1500);
FORCEADD UNIVERSAL_POWER..1
(-3650 2175);
FORCEPROP 3 LASTPIN (-3650 2125) SIG_NAME HSC_VDD\g
J 0
(-3640 2135);
DISPLAY 0.659574 (-3640 2135);
PAINT MONO (-3640 2135);
DISPLAY INVISIBLE (-3640 2135);
FORCEPROP 1 LAST HDL_POWER HSC_VDD
J 1
(-3650 2225);
DISPLAY 0.723404 (-3650 2225);
PAINT GREEN (-3650 2225);
FORCEPROP 2 LAST CDS_LIB logical_power
J 0
(-3650 2175);
DISPLAY INVISIBLE (-3650 2175);
FORCEPROP 2 LAST BOM_COST MIO_VRD_SB
J 0
(-3650 2275);
DISPLAY 0.617021 (-3650 2275);
PAINT PURPLE (-3650 2275);
DISPLAY INVISIBLE (-3650 2275);
FORCEPROP 2 LAST ROOM AUX_SW
J 0
(-3650 2275);
DISPLAY 0.617021 (-3650 2275);
DISPLAY INVISIBLE (-3650 2275);
FORCEPROP 1 LAST PATH I28
J 0
(-3600 2200);
DISPLAY 0.872340 (-3600 2200);
PAINT AQUA (-3600 2200);
DISPLAY INVISIBLE (-3600 2200);
FORCEADD Q_RES..2
(-2000 800);
FORCEPROP 1 LAST LOCATION PR3983
J 0
(-1945 950);
DISPLAY 0.723404 (-1945 950);
PAINT AQUA (-1945 950);
FORCEPROP 0 LAST $SEC 1
J 0
(-1925 1000);
DISPLAY 0.680851 (-1925 1000);
PAINT MONO (-1925 1000);
DISPLAY INVISIBLE (-1925 1000);
FORCEPROP 0 LAST CDS_SEC 1
J 0
(-1925 1000);
DISPLAY 1.021277 (-1925 1000);
DISPLAY INVISIBLE (-1925 1000);
FORCEPROP 1 LASTPIN (-2000 900) $PN 1
J 0
(-1995 862);
DISPLAY 0.787234 (-1995 862);
PAINT MONO (-1995 862);
FORCEPROP 1 LASTPIN (-2000 700) $PN 2
J 0
(-1995 710);
DISPLAY 0.787234 (-1995 710);
PAINT MONO (-1995 710);
FORCEPROP 1 LAST WATTAGE 1/16W
J 0
(-1950 800);
DISPLAY 0.723404 (-1950 800);
PAINT SKYBLUE (-1950 800);
FORCEPROP 1 LAST PACK_TYPE 0402LF
J 0
(-1950 650);
DISPLAY 0.723404 (-1950 650);
PAINT SKYBLUE (-1950 650);
FORCEPROP 1 LAST TOLERANCE 1%
J 0
(-1945 850);
DISPLAY 0.723404 (-1945 850);
PAINT SKYBLUE (-1945 850);
FORCEPROP 1 LAST MATERIAL EMPTY
J 0
(-1950 750);
DISPLAY 0.723404 (-1950 750);
PAINT RED (-1950 750);
FORCEPROP 1 LAST PART_NUMBER CS41002FB09
J 0
(-1950 700);
DISPLAY 0.723404 (-1950 700);
PAINT WHITE (-1950 700);
FORCEPROP 1 LAST VALUE 100K
J 0
(-1945 900);
DISPLAY 0.723404 (-1945 900);
PAINT SKYBLUE (-1945 900);
FORCEPROP 2 LAST CDS_LIB pure_quanta
J 0
(-2000 800);
DISPLAY INVISIBLE (-2000 800);
FORCEPROP 1 LAST PATH I29
J 0
(-1950 975);
DISPLAY 0.978723 (-1950 975);
PAINT WHITE (-1950 975);
DISPLAY INVISIBLE (-1950 975);
FORCEADD UNIVERSAL_GND..1
(-3625 -1625);
FORCEPROP 3 LASTPIN (-3625 -1575) SIG_NAME AGND_HSC\g
J 0
(-3615 -1565);
DISPLAY 0.659574 (-3615 -1565);
PAINT MONO (-3615 -1565);
DISPLAY INVISIBLE (-3615 -1565);
FORCEPROP 1 LAST HDL_POWER AGND_HSC
J 1
(-3600 -1700);
DISPLAY 0.723404 (-3600 -1700);
PAINT GREEN (-3600 -1700);
FORCEPROP 2 LAST CDS_LIB logical_power
J 0
(-3625 -1625);
DISPLAY INVISIBLE (-3625 -1625);
FORCEPROP 1 LAST PATH I3
J 0
(-3550 -1625);
DISPLAY 0.872340 (-3550 -1625);
PAINT AQUA (-3550 -1625);
DISPLAY INVISIBLE (-3550 -1625);
FORCEADD Q_RES..2
(-1525 800);
FORCEPROP 1 LAST LOCATION PR3986
J 0
(-1470 950);
DISPLAY 0.723404 (-1470 950);
PAINT AQUA (-1470 950);
FORCEPROP 0 LAST $SEC 1
J 0
(-1450 1000);
DISPLAY 0.680851 (-1450 1000);
PAINT MONO (-1450 1000);
DISPLAY INVISIBLE (-1450 1000);
FORCEPROP 0 LAST CDS_SEC 1
J 0
(-1450 1000);
DISPLAY 1.021277 (-1450 1000);
DISPLAY INVISIBLE (-1450 1000);
FORCEPROP 1 LASTPIN (-1525 900) $PN 1
J 0
(-1520 862);
DISPLAY 0.787234 (-1520 862);
PAINT MONO (-1520 862);
FORCEPROP 1 LASTPIN (-1525 700) $PN 2
J 0
(-1520 710);
DISPLAY 0.787234 (-1520 710);
PAINT MONO (-1520 710);
FORCEPROP 1 LAST PART_NUMBER CS22002BB01
J 0
(-1475 700);
DISPLAY 0.723404 (-1475 700);
PAINT WHITE (-1475 700);
FORCEPROP 1 LAST VALUE 2K
J 0
(-1470 900);
DISPLAY 0.723404 (-1470 900);
PAINT SKYBLUE (-1470 900);
FORCEPROP 1 LAST TOLERANCE 0.1%
J 0
(-1470 850);
DISPLAY 0.723404 (-1470 850);
PAINT SKYBLUE (-1470 850);
FORCEPROP 1 LAST MATERIAL CHIP
J 0
(-1475 750);
DISPLAY 0.723404 (-1475 750);
PAINT SKYBLUE (-1475 750);
FORCEPROP 1 LAST WATTAGE 1/16W
J 0
(-1475 800);
DISPLAY 0.723404 (-1475 800);
PAINT SKYBLUE (-1475 800);
FORCEPROP 1 LAST PACK_TYPE 0402LF
J 0
(-1475 650);
DISPLAY 0.723404 (-1475 650);
PAINT SKYBLUE (-1475 650);
FORCEPROP 2 LAST CDS_LIB pure_quanta
J 0
(-1525 800);
DISPLAY INVISIBLE (-1525 800);
FORCEPROP 1 LAST PATH I30
J 0
(-1475 975);
DISPLAY 0.978723 (-1475 975);
PAINT WHITE (-1475 975);
DISPLAY INVISIBLE (-1475 975);
FORCEADD OFFPAGE..5
(-1100 1025);
FORCEPROP 2 LAST $XR2 301 
J 0
(-1355 989);
DISPLAY 0.638298 (-1355 989);
PAINT MONO (-1355 989);
FORCEPROP 2 LAST $XR1 303 
J 0
(-1475 1025);
DISPLAY 0.638298 (-1475 1025);
PAINT MONO (-1475 1025);
FORCEPROP 2 LAST $XR0 302 
J 0
(-1355 1025);
DISPLAY 0.638298 (-1355 1025);
PAINT MONO (-1355 1025);
FORCEPROP 2 LAST CDS_LIB standard
J 0
(-1100 1025);
DISPLAY INVISIBLE (-1100 1025);
FORCEPROP 1 LAST COMMENT_BODY TRUE
J 0
(-1000 950);
DISPLAY 1.170213 (-1000 950);
PAINT GREEN (-1000 950);
DISPLAY INVISIBLE (-1000 950);
FORCEPROP 1 LAST OFFPAGE TRUE
J 0
(-775 900);
DISPLAY 0.872340 (-775 900);
PAINT AQUA (-775 900);
DISPLAY INVISIBLE (-775 900);
FORCEPROP 2 LAST PATH I31
J 0
(-1350 1075);
DISPLAY 1.021277 (-1350 1075);
DISPLAY INVISIBLE (-1350 1075);
FORCEADD Q_RES..1
(-1950 1625);
FORCEPROP 1 LAST LOCATION PR3982
J 0
(-2225 1625);
DISPLAY 0.723404 (-2225 1625);
PAINT AQUA (-2225 1625);
FORCEPROP 0 LAST $SEC 1
J 0
(-1900 1700);
DISPLAY 0.680851 (-1900 1700);
PAINT MONO (-1900 1700);
DISPLAY INVISIBLE (-1900 1700);
FORCEPROP 0 LAST CDS_SEC 1
J 0
(-1900 1700);
DISPLAY 1.021277 (-1900 1700);
DISPLAY INVISIBLE (-1900 1700);
FORCEPROP 1 LASTPIN (-2050 1625) $PN 1
J 0
(-2038 1637);
DISPLAY 0.787234 (-2038 1637);
PAINT MONO (-2038 1637);
FORCEPROP 1 LASTPIN (-1850 1625) $PN 2
J 0
(-1888 1637);
DISPLAY 0.787234 (-1888 1637);
PAINT MONO (-1888 1637);
FORCEPROP 1 LAST TOLERANCE 1%
J 0
(-1925 1550);
DISPLAY 0.723404 (-1925 1550);
PAINT SKYBLUE (-1925 1550);
FORCEPROP 1 LAST MATERIAL CHIP
J 0
(-1900 1500);
DISPLAY 0.723404 (-1900 1500);
PAINT SKYBLUE (-1900 1500);
FORCEPROP 1 LAST VALUE 120K
J 2
(-1975 1550);
DISPLAY 0.723404 (-1975 1550);
PAINT SKYBLUE (-1975 1550);
FORCEPROP 1 LAST PACK_TYPE 0402LF
J 0
(-1825 1550);
DISPLAY 0.723404 (-1825 1550);
PAINT SKYBLUE (-1825 1550);
FORCEPROP 1 LAST PART_NUMBER CS41202FB05
J 0
(-1800 1625);
DISPLAY 0.723404 (-1800 1625);
PAINT WHITE (-1800 1625);
FORCEPROP 1 LAST WATTAGE 1/16W
J 2
(-1925 1500);
DISPLAY 0.723404 (-1925 1500);
PAINT SKYBLUE (-1925 1500);
FORCEPROP 2 LAST CDS_LIB pure_quanta
J 0
(-1950 1625);
DISPLAY INVISIBLE (-1950 1625);
FORCEPROP 1 LAST PATH I32
J 0
(-2000 1775);
DISPLAY 0.978723 (-2000 1775);
PAINT WHITE (-2000 1775);
DISPLAY INVISIBLE (-2000 1775);
FORCEADD Q_RES..1
(-1375 1450);
FORCEPROP 1 LAST LOCATION PR3988
J 0
(-1675 1450);
DISPLAY 0.723404 (-1675 1450);
PAINT AQUA (-1675 1450);
FORCEPROP 0 LAST $SEC 1
J 0
(-1250 1525);
DISPLAY 0.680851 (-1250 1525);
PAINT MONO (-1250 1525);
DISPLAY INVISIBLE (-1250 1525);
FORCEPROP 0 LAST CDS_SEC 1
J 0
(-1250 1525);
DISPLAY 1.021277 (-1250 1525);
DISPLAY INVISIBLE (-1250 1525);
FORCEPROP 1 LASTPIN (-1475 1450) $PN 1
J 0
(-1463 1462);
DISPLAY 0.787234 (-1463 1462);
PAINT MONO (-1463 1462);
FORCEPROP 1 LASTPIN (-1275 1450) $PN 2
J 0
(-1313 1462);
DISPLAY 0.787234 (-1313 1462);
PAINT MONO (-1313 1462);
FORCEPROP 1 LAST PACK_TYPE 0402LF
J 0
(-1450 1350);
DISPLAY 0.723404 (-1450 1350);
PAINT SKYBLUE (-1450 1350);
FORCEPROP 1 LAST TOLERANCE 5%
J 0
(-1250 1400);
DISPLAY 0.723404 (-1250 1400);
PAINT SKYBLUE (-1250 1400);
FORCEPROP 1 LAST VALUE 0
J 2
(-1250 1475);
DISPLAY 0.723404 (-1250 1475);
PAINT SKYBLUE (-1250 1475);
FORCEPROP 1 LAST MATERIAL CHIP
J 0
(-1200 1350);
DISPLAY 0.723404 (-1200 1350);
PAINT SKYBLUE (-1200 1350);
FORCEPROP 1 LAST PART_NUMBER CS00002JB13
J 0
(-1700 1400);
DISPLAY 0.723404 (-1700 1400);
PAINT WHITE (-1700 1400);
FORCEPROP 1 LAST WATTAGE 1/16W
J 2
(-1500 1350);
DISPLAY 0.723404 (-1500 1350);
PAINT SKYBLUE (-1500 1350);
FORCEPROP 2 LAST CDS_LIB pure_quanta
J 0
(-1375 1450);
DISPLAY INVISIBLE (-1375 1450);
FORCEPROP 1 LAST PATH I33
J 0
(-1425 1600);
DISPLAY 0.978723 (-1425 1600);
PAINT WHITE (-1425 1600);
DISPLAY INVISIBLE (-1425 1600);
FORCEADD Q_RES..2
(-1000 800);
FORCEPROP 1 LAST LOCATION PR3990
J 0
(-945 950);
DISPLAY 0.723404 (-945 950);
PAINT AQUA (-945 950);
FORCEPROP 0 LAST $SEC 1
J 0
(-925 1000);
DISPLAY 0.680851 (-925 1000);
PAINT MONO (-925 1000);
DISPLAY INVISIBLE (-925 1000);
FORCEPROP 0 LAST CDS_SEC 1
J 0
(-925 1000);
DISPLAY 1.021277 (-925 1000);
DISPLAY INVISIBLE (-925 1000);
FORCEPROP 1 LASTPIN (-1000 900) $PN 1
J 0
(-995 862);
DISPLAY 0.787234 (-995 862);
PAINT MONO (-995 862);
FORCEPROP 1 LASTPIN (-1000 700) $PN 2
J 0
(-995 710);
DISPLAY 0.787234 (-995 710);
PAINT MONO (-995 710);
FORCEPROP 1 LAST TOLERANCE 0.1%
J 0
(-945 850);
DISPLAY 0.723404 (-945 850);
PAINT SKYBLUE (-945 850);
FORCEPROP 1 LAST WATTAGE 1/16W
J 0
(-950 800);
DISPLAY 0.723404 (-950 800);
PAINT SKYBLUE (-950 800);
FORCEPROP 1 LAST PART_NUMBER CS22002BB01
J 0
(-950 700);
DISPLAY 0.723404 (-950 700);
PAINT WHITE (-950 700);
FORCEPROP 1 LAST PACK_TYPE 0402LF
J 0
(-950 650);
DISPLAY 0.723404 (-950 650);
PAINT SKYBLUE (-950 650);
FORCEPROP 1 LAST MATERIAL CHIP
J 0
(-950 750);
DISPLAY 0.723404 (-950 750);
PAINT SKYBLUE (-950 750);
FORCEPROP 1 LAST VALUE 2K
J 0
(-945 900);
DISPLAY 0.723404 (-945 900);
PAINT SKYBLUE (-945 900);
FORCEPROP 2 LAST CDS_LIB pure_quanta
J 0
(-1000 800);
DISPLAY INVISIBLE (-1000 800);
FORCEPROP 1 LAST PATH I34
J 0
(-950 975);
DISPLAY 0.978723 (-950 975);
PAINT WHITE (-950 975);
DISPLAY INVISIBLE (-950 975);
FORCEADD MP5991GLUZ..1
(-25 1550);
FORCEPROP 1 LAST LOCATION PU296
J 0
(-350 2550);
DISPLAY 1.148936 (-350 2550);
PAINT GREEN (-350 2550);
FORCEPROP 2 LAST SEC 1
J 0
(-325 2775);
DISPLAY 0.680851 (-325 2775);
PAINT MONO (-325 2775);
DISPLAY INVISIBLE (-325 2775);
FORCEPROP 2 LASTPIN (-500 1125) $PN 23
J 2
(-510 1135);
DISPLAY 0.680851 (-510 1135);
PAINT MONO (-510 1135);
FORCEPROP 2 LASTPIN (450 1475) $PN 3
J 0
(460 1485);
DISPLAY 0.680851 (460 1485);
PAINT MONO (460 1485);
FORCEPROP 2 LASTPIN (450 1375) $PN 6
J 0
(460 1385);
DISPLAY 0.680851 (460 1385);
PAINT MONO (460 1385);
FORCEPROP 2 LASTPIN (-500 825) $PN 20
J 2
(-510 835);
DISPLAY 0.680851 (-510 835);
PAINT MONO (-510 835);
FORCEPROP 2 LASTPIN (450 1175) $PN 5
J 0
(460 1185);
DISPLAY 0.680851 (460 1185);
PAINT MONO (460 1185);
FORCEPROP 2 LASTPIN (-500 1025) $PN 22
J 2
(-510 1035);
DISPLAY 0.680851 (-510 1035);
PAINT MONO (-510 1035);
FORCEPROP 2 LASTPIN (-500 1625) $PN 8
J 2
(-510 1635);
DISPLAY 0.680851 (-510 1635);
PAINT MONO (-510 1635);
FORCEPROP 2 LASTPIN (450 1275) $PN 7
J 0
(460 1285);
DISPLAY 0.680851 (460 1285);
PAINT MONO (460 1285);
FORCEPROP 2 LASTPIN (-500 1225) $PN 24
J 2
(-510 1235);
DISPLAY 0.680851 (-510 1235);
PAINT MONO (-510 1235);
FORCEPROP 2 LASTPIN (-500 1325) $PN 4
J 2
(-510 1335);
DISPLAY 0.680851 (-510 1335);
PAINT MONO (-510 1335);
FORCEPROP 2 LASTPIN (-500 1525) $PN 17
J 2
(-510 1535);
DISPLAY 0.680851 (-510 1535);
PAINT MONO (-510 1535);
FORCEPROP 2 LASTPIN (450 975) $PN 19
J 0
(460 985);
DISPLAY 0.680851 (460 985);
PAINT MONO (460 985);
FORCEPROP 2 LASTPIN (-500 1725) $PN 21
J 2
(-510 1735);
DISPLAY 0.680851 (-510 1735);
PAINT MONO (-510 1735);
FORCEPROP 2 LASTPIN (-500 2275) $PN 9
J 2
(-510 2285);
DISPLAY 0.680851 (-510 2285);
PAINT MONO (-510 2285);
FORCEPROP 2 LASTPIN (-500 2225) $PN 10
J 2
(-510 2235);
DISPLAY 0.680851 (-510 2235);
PAINT MONO (-510 2235);
FORCEPROP 2 LASTPIN (-500 2175) $PN 11
J 2
(-510 2185);
DISPLAY 0.680851 (-510 2185);
PAINT MONO (-510 2185);
FORCEPROP 2 LASTPIN (-500 2125) $PN 12
J 2
(-510 2135);
DISPLAY 0.680851 (-510 2135);
PAINT MONO (-510 2135);
FORCEPROP 2 LASTPIN (-500 2075) $PN 13
J 2
(-510 2085);
DISPLAY 0.680851 (-510 2085);
PAINT MONO (-510 2085);
FORCEPROP 2 LASTPIN (-500 2025) $PN 14
J 2
(-510 2035);
DISPLAY 0.680851 (-510 2035);
PAINT MONO (-510 2035);
FORCEPROP 2 LASTPIN (-500 1975) $PN 15
J 2
(-510 1985);
DISPLAY 0.680851 (-510 1985);
PAINT MONO (-510 1985);
FORCEPROP 2 LASTPIN (-500 1925) $PN 16
J 2
(-510 1935);
DISPLAY 0.680851 (-510 1935);
PAINT MONO (-510 1935);
FORCEPROP 2 LASTPIN (-500 1875) $PN 33
J 2
(-510 1885);
DISPLAY 0.680851 (-510 1885);
PAINT MONO (-510 1885);
FORCEPROP 2 LASTPIN (450 2275) $PN 1
J 0
(460 2285);
DISPLAY 0.680851 (460 2285);
PAINT MONO (460 2285);
FORCEPROP 2 LASTPIN (450 2225) $PN 2
J 0
(460 2235);
DISPLAY 0.680851 (460 2235);
PAINT MONO (460 2235);
FORCEPROP 2 LASTPIN (450 2175) $PN 25
J 0
(460 2185);
DISPLAY 0.680851 (460 2185);
PAINT MONO (460 2185);
FORCEPROP 2 LASTPIN (450 2125) $PN 26
J 0
(460 2135);
DISPLAY 0.680851 (460 2135);
PAINT MONO (460 2135);
FORCEPROP 2 LASTPIN (450 2075) $PN 27
J 0
(460 2085);
DISPLAY 0.680851 (460 2085);
PAINT MONO (460 2085);
FORCEPROP 2 LASTPIN (450 2025) $PN 28
J 0
(460 2035);
DISPLAY 0.680851 (460 2035);
PAINT MONO (460 2035);
FORCEPROP 2 LASTPIN (450 1975) $PN 29
J 0
(460 1985);
DISPLAY 0.680851 (460 1985);
PAINT MONO (460 1985);
FORCEPROP 2 LASTPIN (450 1925) $PN 30
J 0
(460 1935);
DISPLAY 0.680851 (460 1935);
PAINT MONO (460 1935);
FORCEPROP 2 LASTPIN (450 1875) $PN 31
J 0
(460 1885);
DISPLAY 0.680851 (460 1885);
PAINT MONO (460 1885);
FORCEPROP 2 LASTPIN (450 1825) $PN 32
J 0
(460 1835);
DISPLAY 0.680851 (460 1835);
PAINT MONO (460 1835);
FORCEPROP 2 LASTPIN (450 1075) $PN 18
J 0
(460 1085);
DISPLAY 0.680851 (460 1085);
PAINT MONO (460 1085);
FORCEPROP 2 LAST VALUE MP5991GLU-Z
J 0
(-350 2450);
DISPLAY 1.021277 (-350 2450);
FORCEPROP 1 LAST MATERIAL IC
J 0
(-350 2357);
DISPLAY 0.723404 (-350 2357);
PAINT GREEN (-350 2357);
FORCEPROP 1 LAST PART_NUMBER AL005991A00
J 0
(-350 2400);
DISPLAY 0.723404 (-350 2400);
PAINT GREEN (-350 2400);
FORCEPROP 2 LAST PART_TYPE SMLF
J 0
(-350 2500);
DISPLAY 1.021277 (-350 2500);
FORCEPROP 2 LAST SEC_TYPE 
J 0
(-325 2775);
DISPLAY 1.021277 (-325 2775);
DISPLAY INVISIBLE (-325 2775);
FORCEPROP 1 LAST NEEDS_NO_SIZE TRUE
J 0
(-25 1550);
DISPLAY 0.723404 (-25 1550);
PAINT GREEN (-25 1550);
DISPLAY INVISIBLE (-25 1550);
FORCEPROP 1 LAST CDS_LMAN_SYM_OUTLINE -325,775,325,-775
J 0
(-25 1550);
DISPLAY 0.468085 (-25 1550);
PAINT GREEN (-25 1550);
DISPLAY INVISIBLE (-25 1550);
FORCEPROP 2 LAST CDS_LIB pure_quanta
J 0
(-25 1550);
DISPLAY INVISIBLE (-25 1550);
FORCEPROP 1 LAST PATH I35
J 0
(-25 1550);
DISPLAY 0.723404 (-25 1550);
PAINT GREEN (-25 1550);
DISPLAY INVISIBLE (-25 1550);
FORCEADD UNIVERSAL_POWER..1
(-1000 2425);
FORCEPROP 3 LASTPIN (-1000 2375) SIG_NAME P12V_PSU\g
J 0
(-990 2385);
DISPLAY 0.659574 (-990 2385);
PAINT MONO (-990 2385);
DISPLAY INVISIBLE (-990 2385);
FORCEPROP 1 LAST HDL_POWER P12V_PSU
J 1
(-1000 2475);
DISPLAY 0.723404 (-1000 2475);
PAINT GREEN (-1000 2475);
FORCEPROP 2 LAST ROOM AUX_SW
J 0
(-1000 2525);
DISPLAY 0.617021 (-1000 2525);
DISPLAY INVISIBLE (-1000 2525);
FORCEPROP 2 LAST BOM_COST MIO_VRD_SB
J 0
(-1000 2525);
DISPLAY 0.617021 (-1000 2525);
PAINT PURPLE (-1000 2525);
DISPLAY INVISIBLE (-1000 2525);
FORCEPROP 2 LAST CDS_LIB logical_power
J 0
(-1000 2425);
DISPLAY INVISIBLE (-1000 2425);
FORCEPROP 1 LAST PATH I36
J 0
(-950 2450);
DISPLAY 0.872340 (-950 2450);
PAINT AQUA (-950 2450);
DISPLAY INVISIBLE (-950 2450);
FORCEADD Q_CAP..1
(950 -1950);
FORCEPROP 1 LAST LOCATION PC2227
J 0
(1000 -1875);
DISPLAY 0.723404 (1000 -1875);
PAINT AQUA (1000 -1875);
FORCEPROP 0 LAST $SEC 1
J 0
(1000 -1825);
DISPLAY 0.680851 (1000 -1825);
PAINT MONO (1000 -1825);
DISPLAY INVISIBLE (1000 -1825);
FORCEPROP 0 LAST CDS_SEC 1
J 0
(1000 -1825);
DISPLAY 1.021277 (1000 -1825);
DISPLAY INVISIBLE (1000 -1825);
FORCEPROP 1 LASTPIN (950 -1850) $PN 1
J 0
(960 -1870);
DISPLAY 0.787234 (960 -1870);
PAINT MONO (960 -1870);
FORCEPROP 1 LASTPIN (950 -2050) $PN 2
J 0
(960 -2070);
DISPLAY 0.787234 (960 -2070);
PAINT MONO (960 -2070);
FORCEPROP 1 LAST VALUE 0.068UF
J 0
(1000 -1925);
DISPLAY 0.723404 (1000 -1925);
PAINT SKYBLUE (1000 -1925);
FORCEPROP 1 LAST MATERIAL EMPTY
J 0
(1000 -2025);
DISPLAY 0.723404 (1000 -2025);
PAINT RED (1000 -2025);
FORCEPROP 1 LAST VOLTAGE 16V
J 0
(1000 -1975);
DISPLAY 0.723404 (1000 -1975);
PAINT SKYBLUE (1000 -1975);
FORCEPROP 1 LAST PART_NUMBER CH3683K1B09
J 0
(1000 -2075);
DISPLAY 0.723404 (1000 -2075);
PAINT WHITE (1000 -2075);
FORCEPROP 1 LAST PACK_TYPE 0402
J 0
(1000 -2125);
DISPLAY 0.723404 (1000 -2125);
PAINT SKYBLUE (1000 -2125);
FORCEPROP 1 LAST TOLERANCE 10%
J 0
(1000 -2000);
DISPLAY 0.978723 (1000 -2000);
PAINT SKYBLUE (1000 -2000);
DISPLAY INVISIBLE (1000 -2000);
FORCEPROP 2 LAST CDS_LIB pure_quanta
J 0
(950 -1950);
DISPLAY INVISIBLE (950 -1950);
FORCEPROP 1 LAST PATH I37
J 0
(1000 -1800);
DISPLAY 0.978723 (1000 -1800);
PAINT WHITE (1000 -1800);
DISPLAY INVISIBLE (1000 -1800);
FORCEADD UNIVERSAL_GND..1
(950 -2175);
FORCEPROP 3 LASTPIN (950 -2125) SIG_NAME AGND_HSC\g
J 0
(960 -2115);
DISPLAY 0.659574 (960 -2115);
PAINT MONO (960 -2115);
DISPLAY INVISIBLE (960 -2115);
FORCEPROP 1 LAST HDL_POWER AGND_HSC
J 1
(975 -2250);
DISPLAY 0.723404 (975 -2250);
PAINT GREEN (975 -2250);
FORCEPROP 2 LAST CDS_LIB logical_power
J 0
(950 -2175);
DISPLAY INVISIBLE (950 -2175);
FORCEPROP 1 LAST PATH I38
J 0
(1025 -2175);
DISPLAY 0.872340 (1025 -2175);
PAINT AQUA (1025 -2175);
DISPLAY INVISIBLE (1025 -2175);
FORCEADD Q_RES..1
(1450 -1400);
FORCEPROP 1 LAST LOCATION PR3995
J 0
(1150 -1400);
DISPLAY 0.723404 (1150 -1400);
PAINT AQUA (1150 -1400);
FORCEPROP 0 LAST $SEC 1
J 0
(1600 -1325);
DISPLAY 0.680851 (1600 -1325);
PAINT MONO (1600 -1325);
DISPLAY INVISIBLE (1600 -1325);
FORCEPROP 0 LAST CDS_SEC 1
J 0
(1600 -1325);
DISPLAY 1.021277 (1600 -1325);
DISPLAY INVISIBLE (1600 -1325);
FORCEPROP 1 LASTPIN (1350 -1400) $PN 1
J 0
(1362 -1388);
DISPLAY 0.787234 (1362 -1388);
PAINT MONO (1362 -1388);
FORCEPROP 1 LASTPIN (1550 -1400) $PN 2
J 0
(1512 -1388);
DISPLAY 0.787234 (1512 -1388);
PAINT MONO (1512 -1388);
FORCEPROP 1 LAST WATTAGE 1/16W
J 2
(1325 -1500);
DISPLAY 0.723404 (1325 -1500);
PAINT SKYBLUE (1325 -1500);
FORCEPROP 1 LAST PART_NUMBER CS00002JB13
J 0
(1125 -1450);
DISPLAY 0.723404 (1125 -1450);
PAINT WHITE (1125 -1450);
FORCEPROP 1 LAST PACK_TYPE 0402LF
J 0
(1375 -1500);
DISPLAY 0.723404 (1375 -1500);
PAINT SKYBLUE (1375 -1500);
FORCEPROP 1 LAST TOLERANCE 5%
J 0
(1575 -1450);
DISPLAY 0.723404 (1575 -1450);
PAINT SKYBLUE (1575 -1450);
FORCEPROP 1 LAST VALUE 0
J 2
(1600 -1375);
DISPLAY 0.723404 (1600 -1375);
PAINT SKYBLUE (1600 -1375);
FORCEPROP 1 LAST MATERIAL EMPTY
J 0
(1625 -1500);
DISPLAY 0.723404 (1625 -1500);
PAINT RED (1625 -1500);
FORCEPROP 2 LAST CDS_LIB pure_quanta
J 0
(1450 -1400);
DISPLAY INVISIBLE (1450 -1400);
FORCEPROP 1 LAST PATH I39
J 0
(1400 -1250);
DISPLAY 0.978723 (1400 -1250);
PAINT WHITE (1400 -1250);
DISPLAY INVISIBLE (1400 -1250);
FORCEADD Q_CAP..1
(-3625 -1325);
FORCEPROP 1 LAST LOCATION PC2569
J 0
(-3550 -1175);
DISPLAY 0.723404 (-3550 -1175);
PAINT AQUA (-3550 -1175);
FORCEPROP 0 LAST $SEC 1
J 0
(-3550 -1125);
DISPLAY 0.680851 (-3550 -1125);
PAINT MONO (-3550 -1125);
DISPLAY INVISIBLE (-3550 -1125);
FORCEPROP 0 LAST CDS_SEC 1
J 0
(-3550 -1125);
DISPLAY 1.021277 (-3550 -1125);
DISPLAY INVISIBLE (-3550 -1125);
FORCEPROP 1 LASTPIN (-3625 -1225) $PN 1
J 0
(-3615 -1245);
DISPLAY 0.787234 (-3615 -1245);
PAINT MONO (-3615 -1245);
FORCEPROP 1 LASTPIN (-3625 -1425) $PN 2
J 0
(-3615 -1445);
DISPLAY 0.787234 (-3615 -1445);
PAINT MONO (-3615 -1445);
FORCEPROP 1 LAST VALUE 1UF
J 0
(-3550 -1225);
DISPLAY 0.723404 (-3550 -1225);
PAINT SKYBLUE (-3550 -1225);
FORCEPROP 1 LAST VOLTAGE 25V
J 0
(-3550 -1275);
DISPLAY 0.723404 (-3550 -1275);
PAINT SKYBLUE (-3550 -1275);
FORCEPROP 1 LAST PACK_TYPE C0402
J 0
(-3550 -1425);
DISPLAY 0.723404 (-3550 -1425);
PAINT SKYBLUE (-3550 -1425);
FORCEPROP 1 LAST PART_NUMBER CH5104KEB02
J 0
(-3550 -1375);
DISPLAY 0.723404 (-3550 -1375);
PAINT WHITE (-3550 -1375);
FORCEPROP 1 LAST MATERIAL EMPTY
J 0
(-3550 -1325);
DISPLAY 0.723404 (-3550 -1325);
PAINT RED (-3550 -1325);
FORCEPROP 2 LAST CDS_LIB pure_quanta
J 0
(-3625 -1325);
DISPLAY INVISIBLE (-3625 -1325);
FORCEPROP 1 LAST TOLERANCE 10%
J 0
(-3575 -1375);
DISPLAY 0.978723 (-3575 -1375);
PAINT SKYBLUE (-3575 -1375);
DISPLAY INVISIBLE (-3575 -1375);
FORCEPROP 1 LAST PATH I4
J 0
(-3575 -1175);
DISPLAY 0.978723 (-3575 -1175);
PAINT WHITE (-3575 -1175);
DISPLAY INVISIBLE (-3575 -1175);
FORCEADD Q_RES..1
(1450 -1225);
FORCEPROP 1 LAST LOCATION PR3994
J 0
(1150 -1225);
DISPLAY 0.723404 (1150 -1225);
PAINT AQUA (1150 -1225);
FORCEPROP 0 LAST $SEC 1
J 0
(1600 -1150);
DISPLAY 0.680851 (1600 -1150);
PAINT MONO (1600 -1150);
DISPLAY INVISIBLE (1600 -1150);
FORCEPROP 0 LAST CDS_SEC 1
J 0
(1600 -1150);
DISPLAY 1.021277 (1600 -1150);
DISPLAY INVISIBLE (1600 -1150);
FORCEPROP 1 LASTPIN (1350 -1225) $PN 1
J 0
(1362 -1213);
DISPLAY 0.787234 (1362 -1213);
PAINT MONO (1362 -1213);
FORCEPROP 1 LASTPIN (1550 -1225) $PN 2
J 0
(1512 -1213);
DISPLAY 0.787234 (1512 -1213);
PAINT MONO (1512 -1213);
FORCEPROP 1 LAST WATTAGE 1/16W
J 2
(1325 -1325);
DISPLAY 0.723404 (1325 -1325);
PAINT SKYBLUE (1325 -1325);
FORCEPROP 1 LAST PART_NUMBER CS00002JB13
J 0
(1125 -1275);
DISPLAY 0.723404 (1125 -1275);
PAINT WHITE (1125 -1275);
FORCEPROP 1 LAST PACK_TYPE 0402LF
J 0
(1375 -1325);
DISPLAY 0.723404 (1375 -1325);
PAINT SKYBLUE (1375 -1325);
FORCEPROP 1 LAST MATERIAL EMPTY
J 0
(1625 -1325);
DISPLAY 0.723404 (1625 -1325);
PAINT RED (1625 -1325);
FORCEPROP 1 LAST TOLERANCE 5%
J 0
(1575 -1275);
DISPLAY 0.723404 (1575 -1275);
PAINT SKYBLUE (1575 -1275);
FORCEPROP 1 LAST VALUE 0
J 2
(1600 -1200);
DISPLAY 0.723404 (1600 -1200);
PAINT SKYBLUE (1600 -1200);
FORCEPROP 2 LAST CDS_LIB pure_quanta
J 0
(1450 -1225);
DISPLAY INVISIBLE (1450 -1225);
FORCEPROP 1 LAST PATH I40
J 0
(1400 -1075);
DISPLAY 0.978723 (1400 -1075);
PAINT WHITE (1400 -1075);
DISPLAY INVISIBLE (1400 -1075);
FORCEADD UNIVERSAL_POWER..1
(1075 -350);
FORCEPROP 3 LASTPIN (1075 -400) SIG_NAME P12V_AUX\g
J 0
(1085 -390);
DISPLAY 0.659574 (1085 -390);
PAINT MONO (1085 -390);
DISPLAY INVISIBLE (1085 -390);
FORCEPROP 1 LAST HDL_POWER P12V_AUX
J 1
(1075 -300);
DISPLAY 0.723404 (1075 -300);
PAINT GREEN (1075 -300);
FORCEPROP 2 LAST BOM_COST MIO_VRD_SB
J 0
(1075 -250);
DISPLAY 0.617021 (1075 -250);
PAINT PURPLE (1075 -250);
DISPLAY INVISIBLE (1075 -250);
FORCEPROP 2 LAST ROOM AUX_SW
J 0
(1075 -250);
DISPLAY 0.617021 (1075 -250);
DISPLAY INVISIBLE (1075 -250);
FORCEPROP 2 LAST CDS_LIB logical_power
J 0
(1075 -350);
DISPLAY INVISIBLE (1075 -350);
FORCEPROP 1 LAST PATH I41
J 0
(1125 -325);
DISPLAY 0.872340 (1125 -325);
PAINT AQUA (1125 -325);
DISPLAY INVISIBLE (1125 -325);
FORCEADD OFFPAGE..4
(2225 -1800);
FORCEPROP 2 LAST $XR2 303 
J 0
(2651 -1800);
DISPLAY 0.638298 (2651 -1800);
PAINT MONO (2651 -1800);
FORCEPROP 2 LAST $XR1 302 
J 0
(2531 -1800);
DISPLAY 0.638298 (2531 -1800);
PAINT MONO (2531 -1800);
FORCEPROP 2 LAST $XR0 301 
J 0
(2411 -1800);
DISPLAY 0.638298 (2411 -1800);
PAINT MONO (2411 -1800);
FORCEPROP 2 LAST CDS_LIB standard
J 0
(2225 -1800);
DISPLAY INVISIBLE (2225 -1800);
FORCEPROP 1 LAST OFFPAGE TRUE
J 0
(2550 -1925);
DISPLAY 0.872340 (2550 -1925);
PAINT GREEN (2550 -1925);
DISPLAY INVISIBLE (2550 -1925);
FORCEPROP 1 LAST COMMENT_BODY TRUE
J 0
(2200 -1900);
DISPLAY 0.872340 (2200 -1900);
PAINT GREEN (2200 -1900);
DISPLAY INVISIBLE (2200 -1900);
FORCEPROP 2 LAST PATH I42
J 0
(2675 -1750);
DISPLAY 1.021277 (2675 -1750);
DISPLAY INVISIBLE (2675 -1750);
FORCEADD OFFPAGE..5
R 2
(2225 -1700);
FORCEPROP 2 LAST $XR2 301 
J 0
(2654 -1700);
DISPLAY 0.638298 (2654 -1700);
PAINT MONO (2654 -1700);
FORCEPROP 2 LAST $XR1 303 
J 0
(2534 -1700);
DISPLAY 0.638298 (2534 -1700);
PAINT MONO (2534 -1700);
FORCEPROP 2 LAST $XR0 302 
J 0
(2414 -1700);
DISPLAY 0.638298 (2414 -1700);
PAINT MONO (2414 -1700);
FORCEPROP 1 LAST COMMENT_BODY TRUE
J 2
(2125 -1775);
DISPLAY 1.170213 (2125 -1775);
PAINT GREEN (2125 -1775);
DISPLAY INVISIBLE (2125 -1775);
FORCEPROP 1 LAST OFFPAGE TRUE
J 2
(1900 -1825);
DISPLAY 0.872340 (1900 -1825);
PAINT AQUA (1900 -1825);
DISPLAY INVISIBLE (1900 -1825);
FORCEPROP 2 LAST CDS_LIB standard
J 2
(2225 -1700);
DISPLAY INVISIBLE (2225 -1700);
FORCEPROP 2 LAST PATH I43
J 0
(2675 -1650);
DISPLAY 1.021277 (2675 -1650);
DISPLAY INVISIBLE (2675 -1650);
FORCEADD OFFPAGE..5
R 2
(2225 -1600);
FORCEPROP 2 LAST $XR2 301 
J 0
(2654 -1600);
DISPLAY 0.638298 (2654 -1600);
PAINT MONO (2654 -1600);
FORCEPROP 2 LAST $XR1 303 
J 0
(2534 -1600);
DISPLAY 0.638298 (2534 -1600);
PAINT MONO (2534 -1600);
FORCEPROP 2 LAST $XR0 302 
J 0
(2414 -1600);
DISPLAY 0.638298 (2414 -1600);
PAINT MONO (2414 -1600);
FORCEPROP 2 LAST CDS_LIB standard
J 2
(2225 -1600);
DISPLAY INVISIBLE (2225 -1600);
FORCEPROP 1 LAST OFFPAGE TRUE
J 2
(1900 -1725);
DISPLAY 0.872340 (1900 -1725);
PAINT AQUA (1900 -1725);
DISPLAY INVISIBLE (1900 -1725);
FORCEPROP 1 LAST COMMENT_BODY TRUE
J 2
(2125 -1675);
DISPLAY 1.170213 (2125 -1675);
PAINT GREEN (2125 -1675);
DISPLAY INVISIBLE (2125 -1675);
FORCEPROP 2 LAST PATH I44
J 0
(2675 -1550);
DISPLAY 1.021277 (2675 -1550);
DISPLAY INVISIBLE (2675 -1550);
FORCEADD OFFPAGE..4
(2225 -1400);
FORCEPROP 2 LAST $XR2 303 
J 0
(2651 -1400);
DISPLAY 0.638298 (2651 -1400);
PAINT MONO (2651 -1400);
FORCEPROP 2 LAST $XR1 302 
J 0
(2531 -1400);
DISPLAY 0.638298 (2531 -1400);
PAINT MONO (2531 -1400);
FORCEPROP 2 LAST $XR0 301 
J 0
(2411 -1400);
DISPLAY 0.638298 (2411 -1400);
PAINT MONO (2411 -1400);
FORCEPROP 1 LAST OFFPAGE TRUE
J 0
(2550 -1525);
DISPLAY 0.872340 (2550 -1525);
PAINT GREEN (2550 -1525);
DISPLAY INVISIBLE (2550 -1525);
FORCEPROP 1 LAST COMMENT_BODY TRUE
J 0
(2200 -1500);
DISPLAY 0.872340 (2200 -1500);
PAINT GREEN (2200 -1500);
DISPLAY INVISIBLE (2200 -1500);
FORCEPROP 2 LAST CDS_LIB standard
J 0
(2225 -1400);
DISPLAY INVISIBLE (2225 -1400);
FORCEPROP 2 LAST PATH I45
J 0
(2675 -1350);
DISPLAY 1.021277 (2675 -1350);
DISPLAY INVISIBLE (2675 -1350);
FORCEADD OFFPAGE..5
R 2
(2225 -1225);
FORCEPROP 2 LAST $XR3 301 
J 0
(2774 -1225);
DISPLAY 0.638298 (2774 -1225);
PAINT MONO (2774 -1225);
FORCEPROP 2 LAST $XR2 303 
J 0
(2654 -1225);
DISPLAY 0.638298 (2654 -1225);
PAINT MONO (2654 -1225);
FORCEPROP 2 LAST $XR1 302 
J 0
(2534 -1225);
DISPLAY 0.638298 (2534 -1225);
PAINT MONO (2534 -1225);
FORCEPROP 2 LAST $XR0 215 
J 0
(2414 -1225);
DISPLAY 0.638298 (2414 -1225);
PAINT MONO (2414 -1225);
FORCEPROP 1 LAST OFFPAGE TRUE
J 2
(1900 -1350);
DISPLAY 0.872340 (1900 -1350);
PAINT AQUA (1900 -1350);
DISPLAY INVISIBLE (1900 -1350);
FORCEPROP 1 LAST COMMENT_BODY TRUE
J 2
(2125 -1300);
DISPLAY 1.170213 (2125 -1300);
PAINT GREEN (2125 -1300);
DISPLAY INVISIBLE (2125 -1300);
FORCEPROP 2 LAST CDS_LIB standard
J 0
(2225 -1225);
DISPLAY INVISIBLE (2225 -1225);
FORCEPROP 2 LAST PATH I46
J 0
(2775 -1175);
DISPLAY 1.021277 (2775 -1175);
DISPLAY INVISIBLE (2775 -1175);
FORCEADD UNIVERSAL_GND..1
(950 600);
FORCEPROP 3 LASTPIN (950 650) SIG_NAME AGND_HSC\g
J 0
(960 660);
DISPLAY 0.659574 (960 660);
PAINT MONO (960 660);
DISPLAY INVISIBLE (960 660);
FORCEPROP 1 LAST HDL_POWER AGND_HSC
J 1
(975 525);
DISPLAY 0.723404 (975 525);
PAINT GREEN (975 525);
FORCEPROP 2 LAST CDS_LIB logical_power
J 0
(950 600);
DISPLAY INVISIBLE (950 600);
FORCEPROP 1 LAST PATH I47
J 0
(1025 600);
DISPLAY 0.872340 (1025 600);
PAINT AQUA (1025 600);
DISPLAY INVISIBLE (1025 600);
FORCEADD Q_CAP..1
(950 825);
FORCEPROP 1 LAST LOCATION PC2226
J 0
(1000 900);
DISPLAY 0.723404 (1000 900);
PAINT AQUA (1000 900);
FORCEPROP 0 LAST $SEC 1
J 0
(1000 950);
DISPLAY 0.680851 (1000 950);
PAINT MONO (1000 950);
DISPLAY INVISIBLE (1000 950);
FORCEPROP 0 LAST CDS_SEC 1
J 0
(1000 950);
DISPLAY 1.021277 (1000 950);
DISPLAY INVISIBLE (1000 950);
FORCEPROP 1 LASTPIN (950 925) $PN 1
J 0
(960 905);
DISPLAY 0.787234 (960 905);
PAINT MONO (960 905);
FORCEPROP 1 LASTPIN (950 725) $PN 2
J 0
(960 705);
DISPLAY 0.787234 (960 705);
PAINT MONO (960 705);
FORCEPROP 1 LAST MATERIAL X7R
J 0
(1000 750);
DISPLAY 0.723404 (1000 750);
PAINT SKYBLUE (1000 750);
FORCEPROP 1 LAST VALUE 0.068UF
J 0
(1000 850);
DISPLAY 0.723404 (1000 850);
PAINT SKYBLUE (1000 850);
FORCEPROP 1 LAST VOLTAGE 16V
J 0
(1000 800);
DISPLAY 0.723404 (1000 800);
PAINT SKYBLUE (1000 800);
FORCEPROP 1 LAST PART_NUMBER CH3683K1B09
J 0
(1000 700);
DISPLAY 0.723404 (1000 700);
PAINT WHITE (1000 700);
FORCEPROP 1 LAST PACK_TYPE 0402
J 0
(1000 650);
DISPLAY 0.723404 (1000 650);
PAINT SKYBLUE (1000 650);
FORCEPROP 2 LAST CDS_LIB pure_quanta
J 0
(950 825);
DISPLAY INVISIBLE (950 825);
FORCEPROP 1 LAST TOLERANCE 10%
J 0
(1000 775);
DISPLAY 0.978723 (1000 775);
PAINT SKYBLUE (1000 775);
DISPLAY INVISIBLE (1000 775);
FORCEPROP 1 LAST PATH I48
J 0
(1000 975);
DISPLAY 0.978723 (1000 975);
PAINT WHITE (1000 975);
DISPLAY INVISIBLE (1000 975);
FORCEADD Q_RES..1
(1450 1375);
FORCEPROP 1 LAST LOCATION PR3993
J 0
(1150 1375);
DISPLAY 0.723404 (1150 1375);
PAINT AQUA (1150 1375);
FORCEPROP 0 LAST $SEC 1
J 0
(1600 1450);
DISPLAY 0.680851 (1600 1450);
PAINT MONO (1600 1450);
DISPLAY INVISIBLE (1600 1450);
FORCEPROP 0 LAST CDS_SEC 1
J 0
(1600 1450);
DISPLAY 1.021277 (1600 1450);
DISPLAY INVISIBLE (1600 1450);
FORCEPROP 1 LASTPIN (1350 1375) $PN 1
J 0
(1362 1387);
DISPLAY 0.787234 (1362 1387);
PAINT MONO (1362 1387);
FORCEPROP 1 LASTPIN (1550 1375) $PN 2
J 0
(1512 1387);
DISPLAY 0.787234 (1512 1387);
PAINT MONO (1512 1387);
FORCEPROP 1 LAST PART_NUMBER CS00002JB13
J 0
(1125 1325);
DISPLAY 0.723404 (1125 1325);
PAINT WHITE (1125 1325);
FORCEPROP 1 LAST WATTAGE 1/16W
J 2
(1325 1275);
DISPLAY 0.723404 (1325 1275);
PAINT SKYBLUE (1325 1275);
FORCEPROP 1 LAST PACK_TYPE 0402LF
J 0
(1375 1275);
DISPLAY 0.723404 (1375 1275);
PAINT SKYBLUE (1375 1275);
FORCEPROP 1 LAST VALUE 0
J 2
(1600 1400);
DISPLAY 0.723404 (1600 1400);
PAINT SKYBLUE (1600 1400);
FORCEPROP 1 LAST MATERIAL CHIP
J 0
(1625 1275);
DISPLAY 0.723404 (1625 1275);
PAINT SKYBLUE (1625 1275);
FORCEPROP 1 LAST TOLERANCE 5%
J 0
(1575 1325);
DISPLAY 0.723404 (1575 1325);
PAINT SKYBLUE (1575 1325);
FORCEPROP 2 LAST CDS_LIB pure_quanta
J 0
(1450 1375);
DISPLAY INVISIBLE (1450 1375);
FORCEPROP 1 LAST PATH I49
J 0
(1400 1525);
DISPLAY 0.978723 (1400 1525);
PAINT WHITE (1400 1525);
DISPLAY INVISIBLE (1400 1525);
FORCEADD Q_RES..1
R 1
(-3625 -850);
FORCEPROP 1 LAST LOCATION PR3981
J 0
(-3550 -700);
DISPLAY 0.723404 (-3550 -700);
PAINT AQUA (-3550 -700);
FORCEPROP 0 LAST $SEC 1
R 1
J 0
(-3550 -650);
DISPLAY 0.680851 (-3550 -650);
PAINT MONO (-3550 -650);
DISPLAY INVISIBLE (-3550 -650);
FORCEPROP 0 LAST CDS_SEC 1
R 1
J 0
(-3550 -650);
DISPLAY 1.021277 (-3550 -650);
DISPLAY INVISIBLE (-3550 -650);
FORCEPROP 1 LASTPIN (-3625 -950) $PN 1
R 1
J 0
(-3637 -938);
DISPLAY 0.787234 (-3637 -938);
PAINT MONO (-3637 -938);
FORCEPROP 1 LASTPIN (-3625 -750) $PN 2
R 1
J 0
(-3637 -788);
DISPLAY 0.787234 (-3637 -788);
PAINT MONO (-3637 -788);
FORCEPROP 1 LAST PACK_TYPE 0402LF
J 0
(-3550 -1000);
DISPLAY 0.723404 (-3550 -1000);
PAINT SKYBLUE (-3550 -1000);
FORCEPROP 1 LAST VALUE 0
R 2
J 0
(-3525 -725);
DISPLAY 0.723404 (-3525 -725);
PAINT SKYBLUE (-3525 -725);
FORCEPROP 1 LAST TOLERANCE 5%
J 0
(-3550 -800);
DISPLAY 0.723404 (-3550 -800);
PAINT SKYBLUE (-3550 -800);
FORCEPROP 1 LAST PART_NUMBER CS00002JB13
J 0
(-3550 -950);
DISPLAY 0.723404 (-3550 -950);
PAINT WHITE (-3550 -950);
FORCEPROP 1 LAST WATTAGE 1/16W
J 0
(-3550 -900);
DISPLAY 0.723404 (-3550 -900);
PAINT SKYBLUE (-3550 -900);
FORCEPROP 1 LAST MATERIAL EMPTY
J 0
(-3550 -850);
DISPLAY 0.787234 (-3550 -850);
PAINT RED (-3550 -850);
FORCEPROP 2 LAST CDS_LIB pure_quanta
J 0
(-3625 -850);
DISPLAY INVISIBLE (-3625 -850);
FORCEPROP 1 LAST PATH I5
R 1
J 0
(-3775 -900);
DISPLAY 0.978723 (-3775 -900);
PAINT WHITE (-3775 -900);
DISPLAY INVISIBLE (-3775 -900);
FORCEADD Q_RES..1
(1450 1550);
FORCEPROP 1 LAST LOCATION PR3992
J 0
(1150 1550);
DISPLAY 0.723404 (1150 1550);
PAINT AQUA (1150 1550);
FORCEPROP 0 LAST $SEC 1
J 0
(1600 1625);
DISPLAY 0.680851 (1600 1625);
PAINT MONO (1600 1625);
DISPLAY INVISIBLE (1600 1625);
FORCEPROP 0 LAST CDS_SEC 1
J 0
(1600 1625);
DISPLAY 1.021277 (1600 1625);
DISPLAY INVISIBLE (1600 1625);
FORCEPROP 1 LASTPIN (1350 1550) $PN 1
J 0
(1362 1562);
DISPLAY 0.787234 (1362 1562);
PAINT MONO (1362 1562);
FORCEPROP 1 LASTPIN (1550 1550) $PN 2
J 0
(1512 1562);
DISPLAY 0.787234 (1512 1562);
PAINT MONO (1512 1562);
FORCEPROP 1 LAST WATTAGE 1/16W
J 2
(1325 1450);
DISPLAY 0.723404 (1325 1450);
PAINT SKYBLUE (1325 1450);
FORCEPROP 1 LAST PART_NUMBER CS00002JB13
J 0
(1125 1500);
DISPLAY 0.723404 (1125 1500);
PAINT WHITE (1125 1500);
FORCEPROP 1 LAST TOLERANCE 5%
J 0
(1575 1500);
DISPLAY 0.723404 (1575 1500);
PAINT SKYBLUE (1575 1500);
FORCEPROP 1 LAST MATERIAL CHIP
J 0
(1625 1450);
DISPLAY 0.723404 (1625 1450);
PAINT SKYBLUE (1625 1450);
FORCEPROP 1 LAST PACK_TYPE 0402LF
J 0
(1375 1450);
DISPLAY 0.723404 (1375 1450);
PAINT SKYBLUE (1375 1450);
FORCEPROP 1 LAST VALUE 0
J 2
(1600 1575);
DISPLAY 0.723404 (1600 1575);
PAINT SKYBLUE (1600 1575);
FORCEPROP 2 LAST CDS_LIB pure_quanta
J 0
(1450 1550);
DISPLAY INVISIBLE (1450 1550);
FORCEPROP 1 LAST PATH I50
J 0
(1400 1700);
DISPLAY 0.978723 (1400 1700);
PAINT WHITE (1400 1700);
DISPLAY INVISIBLE (1400 1700);
FORCEADD UNIVERSAL_POWER..1
(1075 2425);
FORCEPROP 3 LASTPIN (1075 2375) SIG_NAME P12V_AUX\g
J 0
(1085 2385);
DISPLAY 0.659574 (1085 2385);
PAINT MONO (1085 2385);
DISPLAY INVISIBLE (1085 2385);
FORCEPROP 1 LAST HDL_POWER P12V_AUX
J 1
(1075 2475);
DISPLAY 0.723404 (1075 2475);
PAINT GREEN (1075 2475);
FORCEPROP 2 LAST BOM_COST MIO_VRD_SB
J 0
(1075 2525);
DISPLAY 0.617021 (1075 2525);
PAINT PURPLE (1075 2525);
DISPLAY INVISIBLE (1075 2525);
FORCEPROP 2 LAST ROOM AUX_SW
J 0
(1075 2525);
DISPLAY 0.617021 (1075 2525);
DISPLAY INVISIBLE (1075 2525);
FORCEPROP 2 LAST CDS_LIB logical_power
J 0
(1075 2425);
DISPLAY INVISIBLE (1075 2425);
FORCEPROP 1 LAST PATH I51
J 0
(1125 2450);
DISPLAY 0.872340 (1125 2450);
PAINT AQUA (1125 2450);
DISPLAY INVISIBLE (1125 2450);
FORCEADD OFFPAGE..4
(2250 975);
FORCEPROP 2 LAST $XR2 303 
J 0
(2676 975);
DISPLAY 0.638298 (2676 975);
PAINT MONO (2676 975);
FORCEPROP 2 LAST $XR1 302 
J 0
(2556 975);
DISPLAY 0.638298 (2556 975);
PAINT MONO (2556 975);
FORCEPROP 2 LAST $XR0 301 
J 0
(2436 975);
DISPLAY 0.638298 (2436 975);
PAINT MONO (2436 975);
FORCEPROP 2 LAST CDS_LIB standard
J 0
(2250 975);
DISPLAY INVISIBLE (2250 975);
FORCEPROP 1 LAST OFFPAGE TRUE
J 0
(2575 850);
DISPLAY 0.872340 (2575 850);
PAINT GREEN (2575 850);
DISPLAY INVISIBLE (2575 850);
FORCEPROP 1 LAST COMMENT_BODY TRUE
J 0
(2225 875);
DISPLAY 0.872340 (2225 875);
PAINT GREEN (2225 875);
DISPLAY INVISIBLE (2225 875);
FORCEPROP 2 LAST PATH I52
J 0
(2700 1025);
DISPLAY 1.021277 (2700 1025);
DISPLAY INVISIBLE (2700 1025);
FORCEADD OFFPAGE..5
R 2
(2250 1075);
FORCEPROP 2 LAST $XR2 301 
J 0
(2679 1075);
DISPLAY 0.638298 (2679 1075);
PAINT MONO (2679 1075);
FORCEPROP 2 LAST $XR1 303 
J 0
(2559 1075);
DISPLAY 0.638298 (2559 1075);
PAINT MONO (2559 1075);
FORCEPROP 2 LAST $XR0 302 
J 0
(2439 1075);
DISPLAY 0.638298 (2439 1075);
PAINT MONO (2439 1075);
FORCEPROP 1 LAST COMMENT_BODY TRUE
J 2
(2150 1000);
DISPLAY 1.170213 (2150 1000);
PAINT GREEN (2150 1000);
DISPLAY INVISIBLE (2150 1000);
FORCEPROP 1 LAST OFFPAGE TRUE
J 2
(1925 950);
DISPLAY 0.872340 (1925 950);
PAINT AQUA (1925 950);
DISPLAY INVISIBLE (1925 950);
FORCEPROP 2 LAST CDS_LIB standard
J 2
(2250 1075);
DISPLAY INVISIBLE (2250 1075);
FORCEPROP 2 LAST PATH I53
J 0
(2700 1125);
DISPLAY 1.021277 (2700 1125);
DISPLAY INVISIBLE (2700 1125);
FORCEADD OFFPAGE..5
R 2
(2250 1175);
FORCEPROP 2 LAST $XR2 301 
J 0
(2679 1175);
DISPLAY 0.638298 (2679 1175);
PAINT MONO (2679 1175);
FORCEPROP 2 LAST $XR1 303 
J 0
(2559 1175);
DISPLAY 0.638298 (2559 1175);
PAINT MONO (2559 1175);
FORCEPROP 2 LAST $XR0 302 
J 0
(2439 1175);
DISPLAY 0.638298 (2439 1175);
PAINT MONO (2439 1175);
FORCEPROP 2 LAST CDS_LIB standard
J 2
(2250 1175);
DISPLAY INVISIBLE (2250 1175);
FORCEPROP 1 LAST OFFPAGE TRUE
J 2
(1925 1050);
DISPLAY 0.872340 (1925 1050);
PAINT AQUA (1925 1050);
DISPLAY INVISIBLE (1925 1050);
FORCEPROP 1 LAST COMMENT_BODY TRUE
J 2
(2150 1100);
DISPLAY 1.170213 (2150 1100);
PAINT GREEN (2150 1100);
DISPLAY INVISIBLE (2150 1100);
FORCEPROP 2 LAST PATH I54
J 0
(2700 1225);
DISPLAY 1.021277 (2700 1225);
DISPLAY INVISIBLE (2700 1225);
FORCEADD OFFPAGE..4
(2250 1375);
FORCEPROP 2 LAST $XR2 303 
J 0
(2676 1375);
DISPLAY 0.638298 (2676 1375);
PAINT MONO (2676 1375);
FORCEPROP 2 LAST $XR1 302 
J 0
(2556 1375);
DISPLAY 0.638298 (2556 1375);
PAINT MONO (2556 1375);
FORCEPROP 2 LAST $XR0 301 
J 0
(2436 1375);
DISPLAY 0.638298 (2436 1375);
PAINT MONO (2436 1375);
FORCEPROP 1 LAST OFFPAGE TRUE
J 0
(2575 1250);
DISPLAY 0.872340 (2575 1250);
PAINT GREEN (2575 1250);
DISPLAY INVISIBLE (2575 1250);
FORCEPROP 1 LAST COMMENT_BODY TRUE
J 0
(2225 1275);
DISPLAY 0.872340 (2225 1275);
PAINT GREEN (2225 1275);
DISPLAY INVISIBLE (2225 1275);
FORCEPROP 2 LAST CDS_LIB standard
J 0
(2250 1375);
DISPLAY INVISIBLE (2250 1375);
FORCEPROP 2 LAST PATH I55
J 0
(2700 1425);
DISPLAY 1.021277 (2700 1425);
DISPLAY INVISIBLE (2700 1425);
FORCEADD OFFPAGE..5
R 2
(2250 1550);
FORCEPROP 2 LAST $XR3 301 
J 0
(2799 1550);
DISPLAY 0.638298 (2799 1550);
PAINT MONO (2799 1550);
FORCEPROP 2 LAST $XR2 303 
J 0
(2679 1550);
DISPLAY 0.638298 (2679 1550);
PAINT MONO (2679 1550);
FORCEPROP 2 LAST $XR1 302 
J 0
(2559 1550);
DISPLAY 0.638298 (2559 1550);
PAINT MONO (2559 1550);
FORCEPROP 2 LAST $XR0 215 
J 0
(2439 1550);
DISPLAY 0.638298 (2439 1550);
PAINT MONO (2439 1550);
FORCEPROP 1 LAST COMMENT_BODY TRUE
J 2
(2150 1475);
DISPLAY 1.170213 (2150 1475);
PAINT GREEN (2150 1475);
DISPLAY INVISIBLE (2150 1475);
FORCEPROP 1 LAST OFFPAGE TRUE
J 2
(1925 1425);
DISPLAY 0.872340 (1925 1425);
PAINT AQUA (1925 1425);
DISPLAY INVISIBLE (1925 1425);
FORCEPROP 2 LAST CDS_LIB standard
J 0
(2250 1550);
DISPLAY INVISIBLE (2250 1550);
FORCEPROP 2 LAST PATH I56
J 0
(2800 1600);
DISPLAY 1.021277 (2800 1600);
DISPLAY INVISIBLE (2800 1600);
FORCEADD UNIVERSAL_POWER..1
(-3625 -600);
FORCEPROP 3 LASTPIN (-3625 -650) SIG_NAME HSC_VDD\g
J 0
(-3615 -640);
DISPLAY 0.659574 (-3615 -640);
PAINT MONO (-3615 -640);
DISPLAY INVISIBLE (-3615 -640);
FORCEPROP 1 LAST HDL_POWER HSC_VDD
J 1
(-3625 -550);
DISPLAY 0.723404 (-3625 -550);
PAINT GREEN (-3625 -550);
FORCEPROP 2 LAST ROOM AUX_SW
J 0
(-3625 -500);
DISPLAY 0.617021 (-3625 -500);
DISPLAY INVISIBLE (-3625 -500);
FORCEPROP 2 LAST BOM_COST MIO_VRD_SB
J 0
(-3625 -500);
DISPLAY 0.617021 (-3625 -500);
PAINT PURPLE (-3625 -500);
DISPLAY INVISIBLE (-3625 -500);
FORCEPROP 2 LAST CDS_LIB logical_power
J 0
(-3625 -600);
DISPLAY INVISIBLE (-3625 -600);
FORCEPROP 1 LAST PATH I6
J 0
(-3575 -575);
DISPLAY 0.872340 (-3575 -575);
PAINT AQUA (-3575 -575);
DISPLAY INVISIBLE (-3575 -575);
FORCEADD OFFPAGE..4
R 2
(-2950 -1450);
FORCEPROP 2 LAST $XR2 303 
J 0
(-3202 -1486);
DISPLAY 0.638298 (-3202 -1486);
PAINT MONO (-3202 -1486);
FORCEPROP 2 LAST $XR1 302 
J 0
(-3322 -1450);
DISPLAY 0.638298 (-3322 -1450);
PAINT MONO (-3322 -1450);
FORCEPROP 2 LAST $XR0 301 
J 0
(-3202 -1450);
DISPLAY 0.638298 (-3202 -1450);
PAINT MONO (-3202 -1450);
FORCEPROP 2 LAST CDS_LIB standard
J 0
(-2950 -1450);
DISPLAY INVISIBLE (-2950 -1450);
FORCEPROP 1 LAST COMMENT_BODY TRUE
J 2
(-2925 -1550);
DISPLAY 0.872340 (-2925 -1550);
PAINT GREEN (-2925 -1550);
DISPLAY INVISIBLE (-2925 -1550);
FORCEPROP 1 LAST OFFPAGE TRUE
J 2
(-3275 -1575);
DISPLAY 0.872340 (-3275 -1575);
PAINT GREEN (-3275 -1575);
DISPLAY INVISIBLE (-3275 -1575);
FORCEPROP 2 LAST PATH I7
J 0
(-3200 -1400);
DISPLAY 1.021277 (-3200 -1400);
DISPLAY INVISIBLE (-3200 -1400);
FORCEADD UNIVERSAL_GND..1
(-2750 -1250);
FORCEPROP 3 LASTPIN (-2750 -1200) SIG_NAME AGND_HSC\g
J 0
(-2740 -1190);
DISPLAY 0.659574 (-2740 -1190);
PAINT MONO (-2740 -1190);
DISPLAY INVISIBLE (-2740 -1190);
FORCEPROP 1 LAST HDL_POWER AGND_HSC
J 1
(-2725 -1325);
DISPLAY 0.723404 (-2725 -1325);
PAINT GREEN (-2725 -1325);
FORCEPROP 2 LAST CDS_LIB logical_power
J 0
(-2750 -1250);
DISPLAY INVISIBLE (-2750 -1250);
FORCEPROP 1 LAST PATH I8
J 0
(-2675 -1250);
DISPLAY 0.872340 (-2675 -1250);
PAINT AQUA (-2675 -1250);
DISPLAY INVISIBLE (-2675 -1250);
FORCEADD OFFPAGE..4
R 2
(-2125 -1550);
FORCEPROP 2 LAST $XR2 303 
J 0
(-2647 -1550);
DISPLAY 0.638298 (-2647 -1550);
PAINT MONO (-2647 -1550);
FORCEPROP 2 LAST $XR1 302 
J 0
(-2527 -1550);
DISPLAY 0.638298 (-2527 -1550);
PAINT MONO (-2527 -1550);
FORCEPROP 2 LAST $XR0 301 
J 0
(-2407 -1550);
DISPLAY 0.638298 (-2407 -1550);
PAINT MONO (-2407 -1550);
FORCEPROP 2 LAST CDS_LIB standard
J 0
(-2125 -1550);
DISPLAY INVISIBLE (-2125 -1550);
FORCEPROP 1 LAST COMMENT_BODY TRUE
J 2
(-2100 -1650);
DISPLAY 0.872340 (-2100 -1650);
PAINT GREEN (-2100 -1650);
DISPLAY INVISIBLE (-2100 -1650);
FORCEPROP 1 LAST OFFPAGE TRUE
J 2
(-2450 -1675);
DISPLAY 0.872340 (-2450 -1675);
PAINT GREEN (-2450 -1675);
DISPLAY INVISIBLE (-2450 -1675);
FORCEPROP 2 LAST PATH I9
J 0
(-2400 -1500);
DISPLAY 1.021277 (-2400 -1500);
DISPLAY INVISIBLE (-2400 -1500);
FORCEADD DNS..2
(-2725 -1975);
PAINT RED (-2725 -1975);
FORCEPROP 2 LAST CDS_LIB mstr_misc
J 0
(-2725 -1975);
DISPLAY INVISIBLE (-2725 -1975);
FORCEPROP 1 LAST COMMENT_BODY TRUE
R 1
J 0
(-2650 -2200);
DISPLAY 0.872340 (-2650 -2200);
PAINT GREEN (-2650 -2200);
DISPLAY INVISIBLE (-2650 -2200);
FORCEADD QUANTA_TITLE_BLOCK_C..1
(4675 -3350);
FORCEPROP 0 LAST CDS_CON_LAST_MODIFIED Fri Dec 10 16:50:58 2021
J 0
(2790 -3335);
PAINT MONO (2790 -3335);
DISPLAY INVISIBLE (2790 -3335);
FORCEPROP 2 LAST CUSTOM_TXT_CDS <XR_PAGE_TITLE>
J 0
(-3215 1900);
DISPLAY 0.638298 (-3215 1900);
PAINT PINK (-3215 1900);
DISPLAY INVISIBLE (-3215 1900);
FORCEPROP 2 LAST CUSTOM_TXT_CDS <CON_LAST_MODIFIED>
J 0
(2790 -3335);
DISPLAY 0.978723 (2790 -3335);
FORCEPROP 2 LAST CUSTOM_TXT_CDS <Q_NUMBER>
J 0
(3272 -3247);
DISPLAY 1.212766 (3272 -3247);
FORCEPROP 2 LAST CUSTOM_TXT_CDS <Q_PROJ>
J 0
(2293 -3248);
DISPLAY 1.212766 (2293 -3248);
FORCEPROP 2 LAST CUSTOM_TXT_CDS <CON_PAGE_NUM> OF <CON_TOTAL_PAGES>
J 0
(4229 -3332);
DISPLAY 0.978723 (4229 -3332);
FORCEPROP 2 LAST CUSTOM_TXT_CDS <Q_REV>
J 0
(4491 -3247);
DISPLAY 1.212766 (4491 -3247);
FORCEPROP 1 LAST CUSTOM_TXT_CDS <NAME_2>
J 0
(1500 -3300);
FORCEPROP 1 LAST CUSTOM_TXT_CDS <NAME_1>
J 0
(1500 -3175);
FORCEPROP 1 LAST Q_TITLE HSC MP5990 (3/4)
J 0
(-4691 -3324);
DISPLAY 2.446809 (-4691 -3324);
PAINT GREEN (-4691 -3324);
FORCEPROP 1 LAST Q_DEPT BU9
J 1
(912 -3301);
DISPLAY 1.957447 (912 -3301);
PAINT GREEN (912 -3301);
FORCEPROP 2 LAST PAGE_BORDER TRUE
J 0
(-3215 1900);
DISPLAY 0.638298 (-3215 1900);
PAINT PINK (-3215 1900);
DISPLAY INVISIBLE (-3215 1900);
FORCEPROP 2 LAST CDS_LIB pure_quanta
J 0
(4675 -3350);
PAINT MONO (4675 -3350);
DISPLAY INVISIBLE (4675 -3350);
FORCEPROP 1 LAST CDS_LMAN_SYM_OUTLINE -9475,6775,100,-125
J 0
(4675 -3350);
DISPLAY 0.468085 (4675 -3350);
PAINT GREEN (4675 -3350);
DISPLAY INVISIBLE (4675 -3350);
FORCEPROP 1 LAST COMMENT_BODY TRUE
J 0
(4687 -3363);
DISPLAY 0.978723 (4687 -3363);
PAINT GREEN (4687 -3363);
DISPLAY INVISIBLE (4687 -3363);
FORCEPROP 2 LAST CDS_XR_PAGE_TITLE CR-303 : @S9S_MB_2U_LIB.S9S_MB_2U(SCH_1):PAGE303
J 0
(-3215 1900);
DISPLAY 0.638298 (-3215 1900);
PAINT PINK (-3215 1900);
DISPLAY INVISIBLE (-3215 1900);
FORCEADD DNS..2
(-3625 -1300);
PAINT RED (-3625 -1300);
FORCEPROP 1 LAST COMMENT_BODY TRUE
R 1
J 0
(-3550 -1525);
DISPLAY 0.872340 (-3550 -1525);
PAINT GREEN (-3550 -1525);
DISPLAY INVISIBLE (-3550 -1525);
FORCEPROP 2 LAST CDS_LIB mstr_misc
J 0
(-3625 -1300);
DISPLAY INVISIBLE (-3625 -1300);
FORCEADD DNS..2
(950 -1925);
PAINT RED (950 -1925);
FORCEPROP 2 LAST CDS_LIB mstr_misc
J 0
(950 -1925);
DISPLAY INVISIBLE (950 -1925);
FORCEPROP 1 LAST COMMENT_BODY TRUE
R 1
J 0
(1025 -2150);
DISPLAY 0.872340 (1025 -2150);
PAINT GREEN (1025 -2150);
DISPLAY INVISIBLE (1025 -2150);
FORCEADD DNS..2
(-2750 825);
PAINT RED (-2750 825);
FORCEPROP 1 LAST COMMENT_BODY TRUE
R 1
J 0
(-2675 600);
DISPLAY 0.872340 (-2675 600);
PAINT GREEN (-2675 600);
DISPLAY INVISIBLE (-2675 600);
FORCEPROP 2 LAST CDS_LIB mstr_misc
J 0
(-2750 825);
DISPLAY INVISIBLE (-2750 825);
FORCEADD DNS..2
(-2025 -1950);
PAINT RED (-2025 -1950);
FORCEPROP 1 LAST COMMENT_BODY TRUE
R 1
J 0
(-1950 -2175);
DISPLAY 0.872340 (-1950 -2175);
PAINT GREEN (-1950 -2175);
DISPLAY INVISIBLE (-1950 -2175);
FORCEPROP 2 LAST CDS_LIB mstr_misc
J 0
(-2025 -1950);
DISPLAY INVISIBLE (-2025 -1950);
FORCEADD DNS..2
(-50 -500);
PAINT RED (-50 -500);
FORCEPROP 1 LAST COMMENT_BODY TRUE
R 1
J 0
(25 -725);
DISPLAY 0.872340 (25 -725);
PAINT GREEN (25 -725);
DISPLAY INVISIBLE (25 -725);
FORCEPROP 2 LAST CDS_LIB mstr_misc
J 0
(-50 -500);
DISPLAY INVISIBLE (-50 -500);
FORCEADD DNS..2
(-1000 -1950);
PAINT RED (-1000 -1950);
FORCEPROP 1 LAST COMMENT_BODY TRUE
R 1
J 0
(-925 -2175);
DISPLAY 0.872340 (-925 -2175);
PAINT GREEN (-925 -2175);
DISPLAY INVISIBLE (-925 -2175);
FORCEPROP 2 LAST CDS_LIB mstr_misc
J 0
(-1000 -1950);
DISPLAY INVISIBLE (-1000 -1950);
FORCEADD DNS..2
(-1525 -1950);
PAINT RED (-1525 -1950);
FORCEPROP 1 LAST COMMENT_BODY TRUE
R 1
J 0
(-1450 -2175);
DISPLAY 0.872340 (-1450 -2175);
PAINT GREEN (-1450 -2175);
DISPLAY INVISIBLE (-1450 -2175);
FORCEPROP 2 LAST CDS_LIB mstr_misc
J 0
(-1525 -1950);
DISPLAY INVISIBLE (-1525 -1950);
FORCEADD DNS..2
(1475 -1400);
PAINT RED (1475 -1400);
FORCEPROP 2 LAST CDS_LIB mstr_misc
J 0
(1475 -1400);
DISPLAY INVISIBLE (1475 -1400);
FORCEPROP 1 LAST COMMENT_BODY TRUE
R 1
J 0
(1550 -1625);
DISPLAY 0.872340 (1550 -1625);
PAINT GREEN (1550 -1625);
DISPLAY INVISIBLE (1550 -1625);
FORCEADD DNS..2
(-1925 -1150);
PAINT RED (-1925 -1150);
FORCEPROP 1 LAST COMMENT_BODY TRUE
R 1
J 0
(-1850 -1375);
DISPLAY 0.872340 (-1850 -1375);
PAINT GREEN (-1850 -1375);
DISPLAY INVISIBLE (-1850 -1375);
FORCEPROP 2 LAST CDS_LIB mstr_misc
J 0
(-1925 -1150);
DISPLAY INVISIBLE (-1925 -1150);
FORCEADD DNS..2
(-1975 850);
PAINT RED (-1975 850);
FORCEPROP 1 LAST COMMENT_BODY TRUE
R 1
J 0
(-1900 625);
DISPLAY 0.872340 (-1900 625);
PAINT GREEN (-1900 625);
DISPLAY INVISIBLE (-1900 625);
FORCEPROP 2 LAST CDS_LIB mstr_misc
J 0
(-1975 850);
DISPLAY INVISIBLE (-1975 850);
FORCEADD DNS..2
(-1325 -1325);
PAINT RED (-1325 -1325);
FORCEPROP 2 LAST CDS_LIB mstr_misc
J 0
(-1325 -1325);
DISPLAY INVISIBLE (-1325 -1325);
FORCEPROP 1 LAST COMMENT_BODY TRUE
R 1
J 0
(-1250 -1550);
DISPLAY 0.872340 (-1250 -1550);
PAINT GREEN (-1250 -1550);
DISPLAY INVISIBLE (-1250 -1550);
FORCEADD DNS..2
(-3600 -850);
PAINT RED (-3600 -850);
FORCEPROP 2 LAST CDS_LIB mstr_misc
J 0
(-3600 -850);
DISPLAY INVISIBLE (-3600 -850);
FORCEPROP 1 LAST COMMENT_BODY TRUE
R 1
J 0
(-3525 -1075);
DISPLAY 0.872340 (-3525 -1075);
PAINT GREEN (-3525 -1075);
DISPLAY INVISIBLE (-3525 -1075);
FORCEADD DNS..2
(1450 -1200);
PAINT RED (1450 -1200);
FORCEPROP 2 LAST CDS_LIB mstr_misc
J 0
(1450 -1200);
DISPLAY INVISIBLE (1450 -1200);
FORCEPROP 1 LAST COMMENT_BODY TRUE
R 1
J 0
(1525 -1425);
DISPLAY 0.872340 (1525 -1425);
PAINT GREEN (1525 -1425);
DISPLAY INVISIBLE (1525 -1425);
WIRE 16 -1 (-3650 1350)(-3650 1200);
WIRE 16 -1 (-3650 2125)(-3650 2025);
WIRE 16 -1 (-3625 -1425)(-3625 -1575);
WIRE 16 -1 (950 -2050)(950 -2125);
WIRE 16 -1 (950 725)(950 650);
WIRE 16 -1 (-3625 -650)(-3625 -750);
WIRE 16 -1 (-3650 1550)(-3650 1725);
WIRE 16 -1 (-3650 1725)(-500 1725);
FORCEPROP 2 LAST SIG_NAME HSC_VDD_R_3
J 0
(-1060 1735);
DISPLAY 0.808511 (-1060 1735);
WIRE 16 -1 (-3650 1825)(-3650 1725);
WIRE 16 -1 (-500 1325)(-2750 1325);
FORCEPROP 2 LAST SIG_NAME HSC_ON
J 0
(-1060 1335);
DISPLAY 0.808511 (-1060 1335);
WIRE 16 -1 (-2875 1325)(-2750 1325);
WIRE 16 -1 (-2750 1325)(-2750 900);
WIRE 16 -1 (-500 825)(-550 825);
WIRE 16 -1 (-550 825)(-550 625);
WIRE 16 -1 (-1000 625)(-550 625);
WIRE 16 -1 (-1000 700)(-1000 625);
WIRE 16 -1 (-1000 625)(-1525 625);
WIRE 16 -1 (-1525 700)(-1525 625);
WIRE 16 -1 (-2000 625)(-1525 625);
WIRE 16 -1 (-2000 700)(-2000 625);
WIRE 16 -1 (-2000 625)(-2750 625);
WIRE 16 -1 (-2750 700)(-2750 625);
WIRE 16 -1 (-2750 550)(-2750 625);
WIRE 16 -1 (-500 -1450)(-2750 -1450);
FORCEPROP 2 LAST SIG_NAME HSC_ON
J 0
(-1035 -1440);
DISPLAY 0.808511 (-1035 -1440);
WIRE 16 -1 (-2750 -1450)(-2900 -1450);
WIRE 16 -1 (-2750 -1450)(-2750 -1875);
WIRE 16 -1 (-2025 -2150)(-1525 -2150);
WIRE 16 -1 (-2025 -2075)(-2025 -2150);
WIRE 16 -1 (-2025 -2150)(-2750 -2150);
WIRE 16 -1 (-1000 -2150)(-1525 -2150);
WIRE 16 -1 (-1525 -2075)(-1525 -2150);
WIRE 16 -1 (-1000 -2075)(-1000 -2150);
WIRE 16 -1 (-1000 -2150)(-550 -2150);
WIRE 16 -1 (-2750 -2075)(-2750 -2150);
WIRE 16 -1 (-2750 -2225)(-2750 -2150);
WIRE 16 -1 (-550 -1950)(-550 -2150);
WIRE 16 -1 (-500 -1950)(-550 -1950);
WIRE 16 -1 (-1000 -450)(-700 -450);
WIRE 16 -1 (-1000 -400)(-1000 -450);
WIRE 16 -1 (-700 -450)(-700 -500);
WIRE 16 -1 (-500 -500)(-700 -500);
WIRE 16 -1 (-700 -500)(-700 -550);
WIRE 16 -1 (-500 -550)(-700 -550);
WIRE 16 -1 (-700 -550)(-700 -600);
WIRE 16 -1 (-500 -600)(-700 -600);
WIRE 16 -1 (-700 -600)(-700 -650);
WIRE 16 -1 (-500 -650)(-700 -650);
WIRE 16 -1 (-700 -650)(-700 -700);
WIRE 16 -1 (-500 -700)(-700 -700);
WIRE 16 -1 (-700 -700)(-700 -750);
WIRE 16 -1 (-500 -750)(-700 -750);
WIRE 16 -1 (-700 -750)(-700 -800);
WIRE 16 -1 (-500 -800)(-700 -800);
WIRE 16 -1 (-700 -800)(-700 -850);
WIRE 16 -1 (-500 -850)(-700 -850);
WIRE 16 -1 (-700 -850)(-700 -900);
WIRE 16 -1 (-700 -900)(-500 -900);
WIRE 16 -1 (-2775 1625)(-2050 1625);
WIRE 16 -1 (-2775 1600)(-2775 1625);
WIRE 16 -1 (-1000 2325)(-700 2325);
WIRE 16 -1 (-1000 2375)(-1000 2325);
WIRE 16 -1 (-700 2325)(-700 2275);
WIRE 16 -1 (-500 2275)(-700 2275);
WIRE 16 -1 (-700 2275)(-700 2225);
WIRE 16 -1 (-500 2225)(-700 2225);
WIRE 16 -1 (-700 2225)(-700 2175);
WIRE 16 -1 (-500 2175)(-700 2175);
WIRE 16 -1 (-700 2175)(-700 2125);
WIRE 16 -1 (-500 2125)(-700 2125);
WIRE 16 -1 (-700 2125)(-700 2075);
WIRE 16 -1 (-500 2075)(-700 2075);
WIRE 16 -1 (-700 2075)(-700 2025);
WIRE 16 -1 (-500 2025)(-700 2025);
WIRE 16 -1 (-700 2025)(-700 1975);
WIRE 16 -1 (-500 1975)(-700 1975);
WIRE 16 -1 (-700 1975)(-700 1925);
WIRE 16 -1 (-500 1925)(-700 1925);
WIRE 16 -1 (-700 1925)(-700 1875);
WIRE 16 -1 (-700 1875)(-500 1875);
WIRE 16 -1 (1075 -400)(1075 -425);
WIRE 16 -1 (1075 -425)(575 -425);
WIRE 16 -1 (575 -425)(575 -500);
WIRE 16 -1 (575 -500)(575 -550);
WIRE 16 -1 (450 -500)(575 -500);
WIRE 16 -1 (575 -550)(575 -600);
WIRE 16 -1 (450 -550)(575 -550);
WIRE 16 -1 (575 -600)(575 -650);
WIRE 16 -1 (450 -600)(575 -600);
WIRE 16 -1 (575 -650)(575 -700);
WIRE 16 -1 (450 -650)(575 -650);
WIRE 16 -1 (575 -700)(575 -750);
WIRE 16 -1 (450 -700)(575 -700);
WIRE 16 -1 (575 -750)(575 -800);
WIRE 16 -1 (450 -750)(575 -750);
WIRE 16 -1 (575 -800)(575 -850);
WIRE 16 -1 (450 -800)(575 -800);
WIRE 16 -1 (575 -850)(575 -900);
WIRE 16 -1 (450 -850)(575 -850);
WIRE 16 -1 (575 -900)(575 -950);
WIRE 16 -1 (450 -900)(575 -900);
WIRE 16 -1 (575 -950)(450 -950);
WIRE 16 -1 (1075 2375)(1075 2350);
WIRE 16 -1 (1075 2350)(575 2350);
WIRE 16 -1 (575 2350)(575 2275);
WIRE 16 -1 (575 2275)(575 2225);
WIRE 16 -1 (450 2275)(575 2275);
WIRE 16 -1 (575 2225)(575 2175);
WIRE 16 -1 (450 2225)(575 2225);
WIRE 16 -1 (575 2175)(575 2125);
WIRE 16 -1 (450 2175)(575 2175);
WIRE 16 -1 (575 2125)(575 2075);
WIRE 16 -1 (450 2125)(575 2125);
WIRE 16 -1 (450 2075)(575 2075);
WIRE 16 -1 (575 2075)(575 2025);
WIRE 16 -1 (575 2025)(575 1975);
WIRE 16 -1 (450 2025)(575 2025);
WIRE 16 -1 (575 1975)(575 1925);
WIRE 16 -1 (450 1975)(575 1975);
WIRE 16 -1 (575 1925)(575 1875);
WIRE 16 -1 (450 1925)(575 1925);
WIRE 16 -1 (575 1875)(575 1825);
WIRE 16 -1 (450 1875)(575 1875);
WIRE 16 -1 (575 1825)(450 1825);
WIRE 16 -1 (-2750 -1150)(-2050 -1150);
WIRE 16 -1 (-2750 -1200)(-2750 -1150);
WIRE 16 -1 (-3625 -950)(-3625 -1050);
WIRE 16 -1 (-3625 -1050)(-500 -1050);
FORCEPROP 2 LAST SIG_NAME HSC_VDD_R_4
J 0
(-1035 -1040);
DISPLAY 0.808511 (-1035 -1040);
WIRE 16 -1 (-3625 -1225)(-3625 -1050);
WIRE 16 -1 (-2025 -1875)(-2025 -1550);
WIRE 16 -1 (-500 -1550)(-2025 -1550);
FORCEPROP 2 LAST SIG_NAME HSC_OCREF
J 0
(-1035 -1540);
DISPLAY 0.808511 (-1035 -1540);
WIRE 16 -1 (-2075 -1550)(-2025 -1550);
WIRE 16 -1 (-500 1125)(-1525 1125);
FORCEPROP 2 LAST SIG_NAME HSC_CS_3
J 0
(-1060 1135);
DISPLAY 0.808511 (-1060 1135);
WIRE 16 -1 (-1525 1125)(-1525 900);
WIRE 16 -1 (-1475 1450)(-2025 1450);
FORCEPROP 2 LAST SIG_NAME HSC_SCREF
J 0
(-2035 1460);
DISPLAY 0.808511 (-2035 1460);
WIRE 16 -1 (450 1075)(2200 1075);
FORCEPROP 2 LAST SIG_NAME HSC_VTEMP
J 0
(565 1085);
DISPLAY 0.808511 (565 1085);
WIRE 16 -1 (-1850 -1150)(-500 -1150);
FORCEPROP 2 LAST SIG_NAME HSC_MODE_4
J 0
(-1035 -1140);
DISPLAY 0.808511 (-1035 -1140);
WIRE 16 -1 (-500 1525)(-925 1525);
FORCEPROP 2 LAST SIG_NAME HSC_SCREF_3
J 0
(-1060 1535);
DISPLAY 0.808511 (-1060 1535);
WIRE 16 -1 (-925 1525)(-925 1450);
WIRE 16 -1 (-925 1450)(-1275 1450);
WIRE 16 -1 (1550 1375)(2200 1375);
FORCEPROP 2 LAST SIG_NAME HSC_FLT_TYPE
J 0
(1690 1385);
DISPLAY 0.808511 (1690 1385);
WIRE 16 -1 (1550 1550)(2200 1550);
FORCEPROP 2 LAST SIG_NAME HSC_D_OC_R
J 0
(1765 1560);
DISPLAY 0.808511 (1765 1560);
WIRE 16 -1 (450 1175)(2200 1175);
FORCEPROP 2 LAST SIG_NAME HSC_FAULT
J 0
(565 1185);
DISPLAY 0.808511 (565 1185);
WIRE 16 -1 (450 1375)(1350 1375);
FORCEPROP 2 LAST SIG_NAME HSC_FLT_TYPE_3
J 0
(565 1385);
DISPLAY 0.808511 (565 1385);
WIRE 16 -1 (450 975)(950 975);
FORCEPROP 2 LAST SIG_NAME HSC_SS
J 0
(565 985);
DISPLAY 0.808511 (565 985);
WIRE 16 -1 (950 975)(2200 975);
WIRE 16 -1 (950 975)(950 925);
WIRE 16 -1 (575 1475)(575 1550);
FORCEPROP 2 LAST SIG_NAME HSC_D_OC_3
J 0
(565 1560);
DISPLAY 0.808511 (565 1560);
WIRE 16 -1 (575 1475)(450 1475);
WIRE 16 -1 (575 1550)(1350 1550);
WIRE 16 -1 (1550 -1400)(2175 -1400);
FORCEPROP 2 LAST SIG_NAME HSC_FLT_TYPE
J 0
(1665 -1390);
DISPLAY 0.808511 (1665 -1390);
WIRE 16 -1 (1550 -1225)(2175 -1225);
FORCEPROP 2 LAST SIG_NAME HSC_D_OC_R
J 0
(1715 -1215);
DISPLAY 0.808511 (1715 -1215);
WIRE 16 -1 (450 -1700)(2175 -1700);
FORCEPROP 2 LAST SIG_NAME HSC_VTEMP
J 0
(540 -1690);
DISPLAY 0.808511 (540 -1690);
WIRE 16 -1 (450 -1600)(2175 -1600);
FORCEPROP 2 LAST SIG_NAME HSC_FAULT
J 0
(540 -1590);
DISPLAY 0.808511 (540 -1590);
WIRE 16 -1 (450 -1400)(1350 -1400);
FORCEPROP 2 LAST SIG_NAME HSC_FLT_TYPE_4
J 0
(540 -1390);
DISPLAY 0.808511 (540 -1390);
WIRE 16 -1 (450 -1800)(950 -1800);
FORCEPROP 2 LAST SIG_NAME HSC_SS
J 0
(540 -1790);
DISPLAY 0.808511 (540 -1790);
WIRE 16 -1 (950 -1800)(2175 -1800);
WIRE 16 -1 (950 -1800)(950 -1850);
WIRE 16 -1 (525 -1300)(525 -1225);
FORCEPROP 2 LAST SIG_NAME HSC_D_OC_4
J 0
(540 -1215);
DISPLAY 0.808511 (540 -1215);
WIRE 16 -1 (525 -1300)(450 -1300);
WIRE 16 -1 (525 -1225)(1350 -1225);
WIRE 16 -1 (-1000 900)(-1000 1025);
WIRE 16 -1 (-500 1025)(-1000 1025);
FORCEPROP 2 LAST SIG_NAME HSC_IMON
J 0
(-1060 1035);
DISPLAY 0.808511 (-1060 1035);
WIRE 16 -1 (-1050 1025)(-1000 1025);
WIRE 16 -1 (-1850 1625)(-500 1625);
FORCEPROP 2 LAST SIG_NAME HSC_MODE_3
J 0
(-1060 1635);
DISPLAY 0.808511 (-1060 1635);
WIRE 16 -1 (-2000 900)(-2000 1225);
WIRE 16 -1 (-2000 1225)(-500 1225);
FORCEPROP 2 LAST SIG_NAME HSC_OCREF
J 0
(-1060 1235);
DISPLAY 0.808511 (-1060 1235);
WIRE 16 -1 (-2050 1225)(-2000 1225);
WIRE 16 -1 (-500 -1250)(-925 -1250);
FORCEPROP 2 LAST SIG_NAME HSC_SCREF_4
J 0
(-1035 -1240);
DISPLAY 0.808511 (-1035 -1240);
WIRE 16 -1 (-925 -1250)(-925 -1325);
WIRE 16 -1 (-925 -1325)(-1250 -1325);
WIRE 16 -1 (-1000 -1875)(-1000 -1750);
WIRE 16 -1 (-500 -1750)(-1000 -1750);
FORCEPROP 2 LAST SIG_NAME HSC_IMON
J 0
(-1035 -1740);
DISPLAY 0.808511 (-1035 -1740);
WIRE 16 -1 (-1050 -1750)(-1000 -1750);
WIRE 16 -1 (-500 -1650)(-1525 -1650);
FORCEPROP 2 LAST SIG_NAME HSC_CS_4
J 0
(-1035 -1640);
DISPLAY 0.808511 (-1035 -1640);
WIRE 16 -1 (-1525 -1650)(-1525 -1875);
WIRE 16 -1 (-1450 -1325)(-2025 -1325);
FORCEPROP 2 LAST SIG_NAME HSC_SCREF
J 0
(-2035 -1315);
DISPLAY 0.808511 (-2035 -1315);
DOT 1 (575 2275);
DOT 1 (575 2225);
DOT 1 (575 2175);
DOT 1 (575 2125);
DOT 1 (575 2075);
DOT 1 (950 975);
DOT 1 (575 2025);
DOT 1 (575 1975);
DOT 1 (575 1925);
DOT 1 (575 1875);
DOT 1 (950 -1800);
DOT 1 (575 -500);
DOT 1 (575 -550);
DOT 1 (575 -600);
DOT 1 (575 -650);
DOT 1 (575 -700);
DOT 1 (575 -750);
DOT 1 (575 -800);
DOT 1 (575 -850);
DOT 1 (575 -900);
DOT 1 (-700 2225);
DOT 1 (-700 2275);
DOT 1 (-700 2175);
DOT 1 (-700 2125);
DOT 1 (-700 2075);
DOT 1 (-700 2025);
DOT 1 (-700 1975);
DOT 1 (-700 1925);
DOT 1 (-1000 1025);
DOT 1 (-2000 1225);
DOT 1 (-1525 625);
DOT 1 (-2000 625);
DOT 1 (-2750 1325);
DOT 1 (-3650 1725);
DOT 1 (-700 -500);
DOT 1 (-700 -550);
DOT 1 (-700 -600);
DOT 1 (-700 -650);
DOT 1 (-700 -700);
DOT 1 (-700 -750);
DOT 1 (-700 -800);
DOT 1 (-700 -850);
DOT 1 (-1000 -1750);
DOT 1 (-2025 -1550);
DOT 1 (-1000 -2150);
DOT 1 (-1525 -2150);
DOT 1 (-2025 -2150);
DOT 1 (-2750 -1450);
DOT 1 (-3625 -1050);
DOT 1 (-2750 -2150);
DOT 1 (-2750 625);
DOT 1 (-1000 625);
FORCENOTE
VOUT SLEW RATE: 2V/MS
(1450 700) 0;
DISPLAY LEFT (1450 700);
DISPLAY 1.021277 (1450 700);
FORCENOTE
SOFT START TIME=6MS.
(1450 766) 0;
DISPLAY LEFT (1450 766);
DISPLAY 1.021277 (1450 766);
FORCENOTE
SOFT START TIME=6MS.
(1450 -2010) 0;
DISPLAY LEFT (1450 -2010);
DISPLAY 1.021277 (1450 -2010);
FORCENOTE
VOUT SLEW RATE: 2V/MS
(1450 -2075) 0;
DISPLAY LEFT (1450 -2075);
DISPLAY 1.021277 (1450 -2075);
FORCENOTE
FOR MP5981:
(-475 390) 0;
DISPLAY LEFT (-475 390);
DISPLAY 1.021277 (-475 390);
FORCENOTE
CHANGE PU296 TO AL005981A00
(-475 260) 0;
DISPLAY LEFT (-475 260);
DISPLAY 1.021277 (-475 260);
FORCENOTE
DNI PR3992, PR3993, PR3988
(-475 325) 0;
DISPLAY LEFT (-475 325);
DISPLAY 1.021277 (-475 325);
FORCENOTE
STILL NEED TO CHANGE TO EF PART
(-1525 -2325) 0;
DISPLAY LEFT (-1525 -2325);
DISPLAY 1.021277 (-1525 -2325);
FORCENOTE
FOR MP5981:
(-500 -2435) 0;
DISPLAY LEFT (-500 -2435);
DISPLAY 1.021277 (-500 -2435);
FORCENOTE
DNI PR3994, PR3995, PR3989
(-500 -2500) 0;
DISPLAY LEFT (-500 -2500);
DISPLAY 1.021277 (-500 -2500);
FORCENOTE
CHANGE PU297 TO AL005981A00
(-500 -2565) 0;
DISPLAY LEFT (-500 -2565);
DISPLAY 1.021277 (-500 -2565);
FORCENOTE
20211116 MODIFY FOR GT
(-1375 3050) 0;
DISPLAY LEFT (-1375 3050);
DISPLAY 2.510638 (-1375 3050);
PAINT PINK (-1375 3050);
FORCENOTE
FPH=220A
(-3825 2934) 0;
DISPLAY LEFT (-3825 2934);
DISPLAY 1.595745 (-3825 2934);
FORCENOTE
OCW=220A
(-4550 2934) 0;
DISPLAY LEFT (-4550 2934);
DISPLAY 1.595745 (-4550 2934);
FORCENOTE
OV =14.333V
(-4525 2850) 0;
DISPLAY LEFT (-4525 2850);
DISPLAY 1.021277 (-4525 2850);
FORCENOTE
UV =10.091V
(-4525 2800) 0;
DISPLAY LEFT (-4525 2800);
DISPLAY 1.021277 (-4525 2800);
FORCENOTE
OCP=240A
(-4550 3009) 0;
DISPLAY LEFT (-4550 3009);
DISPLAY 1.595745 (-4550 3009);
FORCENOTE
ADDRESS 0X20
(-4525 2741) 0;
DISPLAY LEFT (-4525 2741);
DISPLAY 1.021277 (-4525 2741);
FORCENOTE
HOT SWAT CIRCUIT
(-4546 3113) 0;
DISPLAY LEFT (-4546 3113);
DISPLAY 2.000000 (-4546 3113);
FORCENOTE
LATCH OFF MODE
(-4525 2675) 0;
DISPLAY LEFT (-4525 2675);
DISPLAY 1.021277 (-4525 2675);
FORCENOTE
PR3987,PR3991
(-1525 -2250) 0;
DISPLAY LEFT (-1525 -2250);
DISPLAY 1.021277 (-1525 -2250);
FORCENOTE
STILL NEED TO CHANGE TO EF PART
(-1475 475) 0;
DISPLAY LEFT (-1475 475);
DISPLAY 1.021277 (-1475 475);
FORCENOTE
PR3986,PR3990
(-1475 550) 0;
DISPLAY LEFT (-1475 550);
DISPLAY 1.021277 (-1475 550);
QUIT
